FILE_TYPE = MACRO_DRAWING;
SET COLOR_WIRE YELLOW;
SET COLOR_PROP ORANGE;
SET COLOR_DOT WHITE;
SET COLOR_ARC YELLOW;
SET COLOR_BODY GREEN;
SET COLOR_NOTE PURPLE;
SET PROP_DISPLAY VALUE;
SET PAGE_NUMBER P217;
FORCEADD OFFPAGE..1
(-4850 1375);
FORCEPROP 2 LAST $XR0 229 
J 0
(-5102 1375);
DISPLAY 0.638298 (-5102 1375);
PAINT MONO (-5102 1375);
FORCEPROP 2 LAST $XR1 230 
J 0
(-5222 1375);
DISPLAY 0.638298 (-5222 1375);
PAINT MONO (-5222 1375);
FORCEPROP 1 LAST COMMENT_BODY TRUE
J 0
(-4725 1275);
DISPLAY 0.872340 (-4725 1275);
PAINT GREEN (-4725 1275);
DISPLAY INVISIBLE (-4725 1275);
FORCEPROP 1 LAST OFFPAGE TRUE
J 0
(-4525 1250);
DISPLAY 0.872340 (-4525 1250);
PAINT GREEN (-4525 1250);
DISPLAY INVISIBLE (-4525 1250);
FORCEPROP 2 LAST CDS_LIB standard
J 0
(-4850 1375);
PAINT MONO (-4850 1375);
DISPLAY INVISIBLE (-4850 1375);
FORCEPROP 2 LAST PATH I1
J 0
(-5100 1425);
DISPLAY 1.021277 (-5100 1425);
DISPLAY INVISIBLE (-5100 1425);
FORCEADD OFFPAGE..1
(-3100 1925);
FORCEPROP 2 LAST $XR0 229 
J 0
(-3382 1925);
DISPLAY 0.638298 (-3382 1925);
PAINT MONO (-3382 1925);
FORCEPROP 1 LAST COMMENT_BODY TRUE
J 0
(-2975 1825);
DISPLAY 0.872340 (-2975 1825);
PAINT GREEN (-2975 1825);
DISPLAY INVISIBLE (-2975 1825);
FORCEPROP 1 LAST OFFPAGE TRUE
J 0
(-2775 1800);
DISPLAY 0.872340 (-2775 1800);
PAINT GREEN (-2775 1800);
DISPLAY INVISIBLE (-2775 1800);
FORCEPROP 2 LAST CDS_LIB standard
J 0
(-3100 1925);
PAINT MONO (-3100 1925);
DISPLAY INVISIBLE (-3100 1925);
FORCEPROP 2 LAST PATH I10
J 0
(-3375 1975);
DISPLAY 1.021277 (-3375 1975);
DISPLAY INVISIBLE (-3375 1975);
FORCEADD OFFPAGE..1
(-3100 1975);
FORCEPROP 2 LAST $XR0 241 
J 0
(-3382 1975);
DISPLAY 0.638298 (-3382 1975);
PAINT MONO (-3382 1975);
FORCEPROP 1 LAST COMMENT_BODY TRUE
J 0
(-2975 1875);
DISPLAY 0.872340 (-2975 1875);
PAINT GREEN (-2975 1875);
DISPLAY INVISIBLE (-2975 1875);
FORCEPROP 1 LAST OFFPAGE TRUE
J 0
(-2775 1850);
DISPLAY 0.872340 (-2775 1850);
PAINT GREEN (-2775 1850);
DISPLAY INVISIBLE (-2775 1850);
FORCEPROP 2 LAST CDS_LIB standard
J 0
(-3100 1975);
PAINT MONO (-3100 1975);
DISPLAY INVISIBLE (-3100 1975);
FORCEPROP 2 LAST PATH I11
J 0
(-3375 2025);
DISPLAY 1.021277 (-3375 2025);
DISPLAY INVISIBLE (-3375 2025);
FORCEADD UNIVERSAL_GND..1
(-3050 900);
FORCEPROP 3 LASTPIN (-3050 950) SIG_NAME GND\g
J 0
(-3040 960);
DISPLAY 0.659574 (-3040 960);
PAINT MONO (-3040 960);
DISPLAY INVISIBLE (-3040 960);
FORCEPROP 1 LAST HDL_POWER GND
J 1
(-3025 825);
DISPLAY 0.702128 (-3025 825);
PAINT GREEN (-3025 825);
DISPLAY INVISIBLE (-3025 825);
FORCEPROP 2 LAST CDS_LIB logical_power
J 0
(-3050 900);
PAINT MONO (-3050 900);
DISPLAY INVISIBLE (-3050 900);
FORCEPROP 1 LAST PATH I12
J 0
(-2975 900);
DISPLAY 0.872340 (-2975 900);
PAINT AQUA (-2975 900);
DISPLAY INVISIBLE (-2975 900);
FORCEADD Q_RES..2
(-3050 1125);
FORCEPROP 1 LAST PART_NUMBER CS21002FB06
J 0
(-3010 1000);
DISPLAY 0.638298 (-3010 1000);
DISPLAY INVISIBLE (-3010 1000);
FORCEPROP 1 LAST PACK_TYPE 0402LF
J 0
(-3010 950);
DISPLAY 0.638298 (-3010 950);
FORCEPROP 1 LAST MATERIAL CHIP
J 0
(-3010 1050);
DISPLAY 0.638298 (-3010 1050);
FORCEPROP 1 LAST WATTAGE 1/16W
J 0
(-3010 1100);
DISPLAY 0.638298 (-3010 1100);
FORCEPROP 1 LAST TOLERANCE 1%
J 0
(-3005 1150);
DISPLAY 0.638298 (-3005 1150);
FORCEPROP 1 LAST VALUE 1K
J 0
(-3005 1200);
DISPLAY 0.638298 (-3005 1200);
FORCEPROP 1 LAST $LOCATION R678
J 0
(-3005 1250);
DISPLAY 0.978723 (-3005 1250);
FORCEPROP 1 LASTPIN (-3050 1225) $PN 1
J 0
(-3045 1187);
DISPLAY 0.787234 (-3045 1187);
FORCEPROP 1 LASTPIN (-3050 1025) $PN 2
J 0
(-3045 1035);
DISPLAY 0.787234 (-3045 1035);
FORCEPROP 2 LAST CDS_LIB pure_quanta
J 0
(-3050 1125);
PAINT MONO (-3050 1125);
DISPLAY INVISIBLE (-3050 1125);
FORCEPROP 1 LAST PATH I13
J 0
(-3000 1300);
DISPLAY 0.978723 (-3000 1300);
PAINT WHITE (-3000 1300);
DISPLAY INVISIBLE (-3000 1300);
FORCEPROP 2 LAST CDS_LOCATION R678
J 0
(-3000 1350);
DISPLAY 1.021277 (-3000 1350);
DISPLAY INVISIBLE (-3000 1350);
FORCEPROP 2 LAST $SEC 1
J 0
(-3000 1350);
DISPLAY 0.680851 (-3000 1350);
PAINT MONO (-3000 1350);
DISPLAY INVISIBLE (-3000 1350);
FORCEPROP 2 LAST CDS_SEC 1
J 0
(-3000 1350);
DISPLAY 1.021277 (-3000 1350);
DISPLAY INVISIBLE (-3000 1350);
FORCEADD OFFPAGE..1
(-3100 3975);
FORCEPROP 2 LAST $XR0 13 
J 0
(-3351 3975);
DISPLAY 0.638298 (-3351 3975);
PAINT MONO (-3351 3975);
FORCEPROP 1 LAST COMMENT_BODY TRUE
J 0
(-2975 3875);
DISPLAY 0.872340 (-2975 3875);
PAINT GREEN (-2975 3875);
DISPLAY INVISIBLE (-2975 3875);
FORCEPROP 1 LAST OFFPAGE TRUE
J 0
(-2775 3850);
DISPLAY 0.872340 (-2775 3850);
PAINT GREEN (-2775 3850);
DISPLAY INVISIBLE (-2775 3850);
FORCEPROP 2 LAST CDS_LIB standard
J 0
(-3100 3975);
PAINT MONO (-3100 3975);
DISPLAY INVISIBLE (-3100 3975);
FORCEPROP 2 LAST PATH I14
J 0
(-3350 4025);
DISPLAY 1.021277 (-3350 4025);
DISPLAY INVISIBLE (-3350 4025);
FORCEADD OFFPAGE..3
R 2
(-3100 3925);
FORCEPROP 2 LAST $XR0 13 
J 0
(-3379 3925);
DISPLAY 0.638298 (-3379 3925);
PAINT MONO (-3379 3925);
FORCEPROP 1 LAST COMMENT_BODY TRUE
J 2
(-3050 3825);
DISPLAY 0.872340 (-3050 3825);
PAINT GREEN (-3050 3825);
DISPLAY INVISIBLE (-3050 3825);
FORCEPROP 1 LAST OFFPAGE TRUE
J 2
(-3425 3800);
DISPLAY 0.872340 (-3425 3800);
DISPLAY INVISIBLE (-3425 3800);
FORCEPROP 2 LAST CDS_LIB standard
J 0
(-3100 3925);
PAINT MONO (-3100 3925);
DISPLAY INVISIBLE (-3100 3925);
FORCEPROP 2 LAST PATH I15
J 0
(-3375 3975);
DISPLAY 1.021277 (-3375 3975);
DISPLAY INVISIBLE (-3375 3975);
FORCEADD Q_RES..1
(-1375 675);
FORCEPROP 1 LAST PART_NUMBER CS00002JB13
J 0
(-1425 725);
DISPLAY 0.404255 (-1425 725);
DISPLAY INVISIBLE (-1425 725);
FORCEPROP 1 LAST MATERIAL EMPTY
J 0
(-1125 675);
DISPLAY 0.510638 (-1125 675);
PAINT RED (-1125 675);
FORCEPROP 1 LAST PACK_TYPE 0402LF
J 0
(-1425 750);
DISPLAY 0.404255 (-1425 750);
FORCEPROP 1 LAST TOLERANCE 5%
J 0
(-1200 675);
DISPLAY 0.510638 (-1200 675);
FORCEPROP 1 LAST VALUE 0
J 2
(-1225 675);
DISPLAY 0.510638 (-1225 675);
FORCEPROP 1 LAST WATTAGE 1/16W
J 2
(-1200 750);
DISPLAY 0.404255 (-1200 750);
FORCEPROP 1 LAST $LOCATION R685
J 0
(-1575 675);
DISPLAY 0.638298 (-1575 675);
FORCEPROP 1 LASTPIN (-1475 675) $PN 1
J 0
(-1463 687);
DISPLAY 0.787234 (-1463 687);
FORCEPROP 1 LASTPIN (-1275 675) $PN 2
J 0
(-1313 687);
DISPLAY 0.787234 (-1313 687);
FORCEPROP 2 LAST CDS_LIB pure_quanta
J 0
(-1375 675);
PAINT MONO (-1375 675);
DISPLAY INVISIBLE (-1375 675);
FORCEPROP 1 LAST PATH I16
J 0
(-1425 825);
DISPLAY 0.978723 (-1425 825);
PAINT WHITE (-1425 825);
DISPLAY INVISIBLE (-1425 825);
FORCEPROP 2 LAST CDS_LOCATION R685
J 0
(-1425 875);
DISPLAY 1.021277 (-1425 875);
DISPLAY INVISIBLE (-1425 875);
FORCEPROP 2 LAST $SEC 1
J 0
(-1425 875);
DISPLAY 0.680851 (-1425 875);
PAINT MONO (-1425 875);
DISPLAY INVISIBLE (-1425 875);
FORCEPROP 2 LAST CDS_SEC 1
J 0
(-1425 875);
DISPLAY 1.021277 (-1425 875);
DISPLAY INVISIBLE (-1425 875);
FORCEADD Q_RES..1
(-1375 800);
FORCEPROP 1 LAST PART_NUMBER CS00002JB13
J 0
(-1425 850);
DISPLAY 0.404255 (-1425 850);
DISPLAY INVISIBLE (-1425 850);
FORCEPROP 1 LAST PACK_TYPE 0402LF
J 0
(-1425 875);
DISPLAY 0.404255 (-1425 875);
FORCEPROP 1 LAST MATERIAL EMPTY
J 0
(-1125 800);
DISPLAY 0.510638 (-1125 800);
PAINT RED (-1125 800);
FORCEPROP 1 LAST TOLERANCE 5%
J 0
(-1200 800);
DISPLAY 0.510638 (-1200 800);
FORCEPROP 1 LAST VALUE 0
J 2
(-1225 800);
DISPLAY 0.510638 (-1225 800);
FORCEPROP 1 LAST WATTAGE 1/16W
J 2
(-1200 875);
DISPLAY 0.404255 (-1200 875);
FORCEPROP 1 LAST $LOCATION R684
J 0
(-1575 800);
DISPLAY 0.638298 (-1575 800);
FORCEPROP 1 LASTPIN (-1475 800) $PN 1
J 0
(-1463 812);
DISPLAY 0.787234 (-1463 812);
FORCEPROP 1 LASTPIN (-1275 800) $PN 2
J 0
(-1313 812);
DISPLAY 0.787234 (-1313 812);
FORCEPROP 2 LAST CDS_LIB pure_quanta
J 0
(-1375 800);
PAINT MONO (-1375 800);
DISPLAY INVISIBLE (-1375 800);
FORCEPROP 1 LAST PATH I17
J 0
(-1425 950);
DISPLAY 0.978723 (-1425 950);
PAINT WHITE (-1425 950);
DISPLAY INVISIBLE (-1425 950);
FORCEPROP 2 LAST CDS_LOCATION R684
J 0
(-1425 1000);
DISPLAY 1.021277 (-1425 1000);
DISPLAY INVISIBLE (-1425 1000);
FORCEPROP 2 LAST $SEC 1
J 0
(-1425 1000);
DISPLAY 0.680851 (-1425 1000);
PAINT MONO (-1425 1000);
DISPLAY INVISIBLE (-1425 1000);
FORCEPROP 2 LAST CDS_SEC 1
J 0
(-1425 1000);
DISPLAY 1.021277 (-1425 1000);
DISPLAY INVISIBLE (-1425 1000);
FORCEADD Q_RES..1
(-1375 925);
FORCEPROP 1 LAST PART_NUMBER CS00002JB13
J 0
(-1425 975);
DISPLAY 0.404255 (-1425 975);
DISPLAY INVISIBLE (-1425 975);
FORCEPROP 1 LAST MATERIAL EMPTY
J 0
(-1125 925);
DISPLAY 0.510638 (-1125 925);
PAINT RED (-1125 925);
FORCEPROP 1 LAST VALUE 0
J 2
(-1225 925);
DISPLAY 0.510638 (-1225 925);
FORCEPROP 1 LAST TOLERANCE 5%
J 0
(-1200 925);
DISPLAY 0.510638 (-1200 925);
FORCEPROP 1 LAST PACK_TYPE 0402LF
J 0
(-1425 1000);
DISPLAY 0.404255 (-1425 1000);
FORCEPROP 1 LAST WATTAGE 1/16W
J 2
(-1200 1000);
DISPLAY 0.404255 (-1200 1000);
FORCEPROP 1 LAST $LOCATION R683
J 0
(-1575 925);
DISPLAY 0.638298 (-1575 925);
FORCEPROP 1 LASTPIN (-1475 925) $PN 1
J 0
(-1463 937);
DISPLAY 0.787234 (-1463 937);
FORCEPROP 1 LASTPIN (-1275 925) $PN 2
J 0
(-1313 937);
DISPLAY 0.787234 (-1313 937);
FORCEPROP 2 LAST CDS_LIB pure_quanta
J 0
(-1375 925);
PAINT MONO (-1375 925);
DISPLAY INVISIBLE (-1375 925);
FORCEPROP 1 LAST PATH I18
J 0
(-1425 1075);
DISPLAY 0.978723 (-1425 1075);
PAINT WHITE (-1425 1075);
DISPLAY INVISIBLE (-1425 1075);
FORCEPROP 2 LAST CDS_LOCATION R683
J 0
(-1425 1125);
DISPLAY 1.021277 (-1425 1125);
DISPLAY INVISIBLE (-1425 1125);
FORCEPROP 2 LAST $SEC 1
J 0
(-1425 1125);
DISPLAY 0.680851 (-1425 1125);
PAINT MONO (-1425 1125);
DISPLAY INVISIBLE (-1425 1125);
FORCEPROP 2 LAST CDS_SEC 1
J 0
(-1425 1125);
DISPLAY 1.021277 (-1425 1125);
DISPLAY INVISIBLE (-1425 1125);
FORCEADD QS3VH257QG8..1
R 2
(-1350 1650);
FORCEPROP 1 LAST PART_NUMBER AL000257W24
J 2
(-1200 2085);
DISPLAY 0.723404 (-1200 2085);
PAINT GREEN (-1200 2085);
DISPLAY INVISIBLE (-1200 2085);
FORCEPROP 2 LAST PACK_TYPE SMLF
J 2
(-1200 2175);
DISPLAY 1.021277 (-1200 2175);
FORCEPROP 2 LAST VALUE QS3VH257QG8
J 2
(-1200 2225);
DISPLAY 1.021277 (-1200 2225);
FORCEPROP 1 LAST MATERIAL IC
J 2
(-1200 2035);
DISPLAY 0.723404 (-1200 2035);
PAINT GREEN (-1200 2035);
FORCEPROP 1 LAST LOCATION U15
J 2
(-1200 2130);
DISPLAY 0.723404 (-1200 2130);
PAINT GREEN (-1200 2130);
FORCEPROP 0 LASTPIN (-1650 1325) $PN 15
J 2
(-1660 1335);
DISPLAY 0.680851 (-1660 1335);
PAINT MONO (-1660 1335);
FORCEPROP 0 LASTPIN (-1050 1325) $PN 8
J 0
(-1040 1335);
DISPLAY 0.680851 (-1040 1335);
PAINT MONO (-1040 1335);
FORCEPROP 0 LASTPIN (-1650 1925) $PN 2
J 2
(-1660 1935);
DISPLAY 0.680851 (-1660 1935);
PAINT MONO (-1660 1935);
FORCEPROP 0 LASTPIN (-1650 1775) $PN 5
J 2
(-1660 1785);
DISPLAY 0.680851 (-1660 1785);
PAINT MONO (-1660 1785);
FORCEPROP 0 LASTPIN (-1650 1625) $PN 11
J 2
(-1660 1635);
DISPLAY 0.680851 (-1660 1635);
PAINT MONO (-1660 1635);
FORCEPROP 0 LASTPIN (-1650 1475) $PN 14
J 2
(-1660 1485);
DISPLAY 0.680851 (-1660 1485);
PAINT MONO (-1660 1485);
FORCEPROP 0 LASTPIN (-1650 1975) $PN 3
J 2
(-1660 1985);
DISPLAY 0.680851 (-1660 1985);
PAINT MONO (-1660 1985);
FORCEPROP 0 LASTPIN (-1650 1825) $PN 6
J 2
(-1660 1835);
DISPLAY 0.680851 (-1660 1835);
PAINT MONO (-1660 1835);
FORCEPROP 0 LASTPIN (-1650 1675) $PN 10
J 2
(-1660 1685);
DISPLAY 0.680851 (-1660 1685);
PAINT MONO (-1660 1685);
FORCEPROP 0 LASTPIN (-1650 1525) $PN 13
J 2
(-1660 1535);
DISPLAY 0.680851 (-1660 1535);
PAINT MONO (-1660 1535);
FORCEPROP 0 LASTPIN (-1650 1375) $PN 1
J 2
(-1660 1385);
DISPLAY 0.680851 (-1660 1385);
PAINT MONO (-1660 1385);
FORCEPROP 0 LASTPIN (-1050 1975) $PN 16
J 0
(-1040 1985);
DISPLAY 0.680851 (-1040 1985);
PAINT MONO (-1040 1985);
FORCEPROP 0 LASTPIN (-1050 1925) $PN 4
J 0
(-1040 1935);
DISPLAY 0.680851 (-1040 1935);
PAINT MONO (-1040 1935);
FORCEPROP 0 LASTPIN (-1050 1775) $PN 7
J 0
(-1040 1785);
DISPLAY 0.680851 (-1040 1785);
PAINT MONO (-1040 1785);
FORCEPROP 0 LASTPIN (-1050 1625) $PN 9
J 0
(-1040 1635);
DISPLAY 0.680851 (-1040 1635);
PAINT MONO (-1040 1635);
FORCEPROP 0 LASTPIN (-1050 1475) $PN 12
J 0
(-1040 1485);
DISPLAY 0.680851 (-1040 1485);
PAINT MONO (-1040 1485);
FORCEPROP 1 LAST NEEDS_NO_SIZE TRUE
J 2
(-1350 1650);
DISPLAY 0.468085 (-1350 1650);
PAINT GREEN (-1350 1650);
DISPLAY INVISIBLE (-1350 1650);
FORCEPROP 2 LAST CDS_LIB pure_quanta
J 2
(-1350 1650);
DISPLAY INVISIBLE (-1350 1650);
FORCEPROP 1 LAST CDS_LMAN_SYM_OUTLINE -150,375,150,-375
J 2
(-1350 1650);
DISPLAY 0.468085 (-1350 1650);
PAINT GREEN (-1350 1650);
DISPLAY INVISIBLE (-1350 1650);
FORCEPROP 1 LAST PATH I19
J 2
(-1475 2030);
DISPLAY 0.723404 (-1475 2030);
PAINT GREEN (-1475 2030);
DISPLAY INVISIBLE (-1475 2030);
FORCEPROP 0 LAST $SEC 1
J 0
(-1200 2275);
DISPLAY 0.680851 (-1200 2275);
PAINT MONO (-1200 2275);
DISPLAY INVISIBLE (-1200 2275);
FORCEPROP 0 LAST CDS_SEC 1
J 0
(-1200 2275);
DISPLAY 1.021277 (-1200 2275);
DISPLAY INVISIBLE (-1200 2275);
FORCEADD OFFPAGE..1
(-4850 1200);
FORCEPROP 2 LAST $XR0 215 
J 0
(-5102 1200);
DISPLAY 0.638298 (-5102 1200);
PAINT MONO (-5102 1200);
FORCEPROP 1 LAST COMMENT_BODY TRUE
J 0
(-4725 1100);
DISPLAY 0.872340 (-4725 1100);
PAINT GREEN (-4725 1100);
DISPLAY INVISIBLE (-4725 1100);
FORCEPROP 1 LAST OFFPAGE TRUE
J 0
(-4525 1075);
DISPLAY 0.872340 (-4525 1075);
PAINT GREEN (-4525 1075);
DISPLAY INVISIBLE (-4525 1075);
FORCEPROP 2 LAST CDS_LIB standard
J 0
(-4850 1200);
PAINT MONO (-4850 1200);
DISPLAY INVISIBLE (-4850 1200);
FORCEPROP 2 LAST PATH I2
J 0
(-5100 1250);
DISPLAY 1.021277 (-5100 1250);
DISPLAY INVISIBLE (-5100 1250);
FORCEADD Q_RES..1
(-1375 1050);
FORCEPROP 1 LAST PART_NUMBER CS00002JB13
J 0
(-1425 1100);
DISPLAY 0.404255 (-1425 1100);
DISPLAY INVISIBLE (-1425 1100);
FORCEPROP 1 LAST VALUE 0
J 2
(-1225 1050);
DISPLAY 0.510638 (-1225 1050);
FORCEPROP 1 LAST TOLERANCE 5%
J 0
(-1200 1050);
DISPLAY 0.510638 (-1200 1050);
FORCEPROP 1 LAST PACK_TYPE 0402LF
J 0
(-1425 1125);
DISPLAY 0.404255 (-1425 1125);
FORCEPROP 1 LAST WATTAGE 1/16W
J 2
(-1200 1125);
DISPLAY 0.404255 (-1200 1125);
FORCEPROP 1 LAST MATERIAL EMPTY
J 0
(-1125 1050);
DISPLAY 0.510638 (-1125 1050);
PAINT RED (-1125 1050);
FORCEPROP 1 LAST $LOCATION R682
J 0
(-1575 1050);
DISPLAY 0.638298 (-1575 1050);
FORCEPROP 1 LASTPIN (-1475 1050) $PN 1
J 0
(-1463 1062);
DISPLAY 0.787234 (-1463 1062);
FORCEPROP 1 LASTPIN (-1275 1050) $PN 2
J 0
(-1313 1062);
DISPLAY 0.787234 (-1313 1062);
FORCEPROP 2 LAST CDS_LIB pure_quanta
J 0
(-1375 1050);
PAINT MONO (-1375 1050);
DISPLAY INVISIBLE (-1375 1050);
FORCEPROP 1 LAST PATH I20
J 0
(-1425 1200);
DISPLAY 0.978723 (-1425 1200);
PAINT WHITE (-1425 1200);
DISPLAY INVISIBLE (-1425 1200);
FORCEPROP 2 LAST CDS_LOCATION R682
J 0
(-1425 1250);
DISPLAY 1.021277 (-1425 1250);
DISPLAY INVISIBLE (-1425 1250);
FORCEPROP 2 LAST $SEC 1
J 0
(-1425 1250);
DISPLAY 0.680851 (-1425 1250);
PAINT MONO (-1425 1250);
DISPLAY INVISIBLE (-1425 1250);
FORCEPROP 2 LAST CDS_SEC 1
J 0
(-1425 1250);
DISPLAY 1.021277 (-1425 1250);
DISPLAY INVISIBLE (-1425 1250);
FORCEADD UNIVERSAL_GND..1
(-975 1200);
FORCEPROP 3 LASTPIN (-975 1250) SIG_NAME GND\g
J 0
(-965 1260);
DISPLAY 0.659574 (-965 1260);
PAINT MONO (-965 1260);
DISPLAY INVISIBLE (-965 1260);
FORCEPROP 1 LAST HDL_POWER GND
J 1
(-950 1125);
DISPLAY 0.702128 (-950 1125);
PAINT GREEN (-950 1125);
DISPLAY INVISIBLE (-950 1125);
FORCEPROP 2 LAST CDS_LIB logical_power
J 0
(-975 1200);
PAINT MONO (-975 1200);
DISPLAY INVISIBLE (-975 1200);
FORCEPROP 1 LAST PATH I21
J 0
(-900 1200);
DISPLAY 0.872340 (-900 1200);
PAINT AQUA (-900 1200);
DISPLAY INVISIBLE (-900 1200);
FORCEADD UNIVERSAL_GND..1
(-750 2000);
FORCEPROP 3 LASTPIN (-750 2050) SIG_NAME GND\g
J 0
(-740 2060);
DISPLAY 0.659574 (-740 2060);
PAINT MONO (-740 2060);
DISPLAY INVISIBLE (-740 2060);
FORCEPROP 1 LAST HDL_POWER GND
J 1
(-725 1925);
DISPLAY 0.872340 (-725 1925);
PAINT GREEN (-725 1925);
DISPLAY INVISIBLE (-725 1925);
FORCEPROP 2 LAST CDS_LIB logical_power
J 0
(-750 2000);
PAINT MONO (-750 2000);
DISPLAY INVISIBLE (-750 2000);
FORCEPROP 1 LAST PATH I22
J 0
(-675 2000);
DISPLAY 0.872340 (-675 2000);
PAINT AQUA (-675 2000);
DISPLAY INVISIBLE (-675 2000);
FORCEADD UNIVERSAL_POWER..1
(-975 2575);
FORCEPROP 3 LASTPIN (-975 2525) SIG_NAME P3V3_AUX\g
J 0
(-965 2535);
DISPLAY 0.659574 (-965 2535);
PAINT MONO (-965 2535);
DISPLAY INVISIBLE (-965 2535);
FORCEPROP 1 LAST HDL_POWER P3V3_AUX
J 1
(-975 2625);
DISPLAY 0.702128 (-975 2625);
PAINT GREEN (-975 2625);
FORCEPROP 2 LAST CDS_LIB logical_power
J 0
(-975 2575);
DISPLAY INVISIBLE (-975 2575);
FORCEPROP 1 LAST PATH I23
J 0
(-925 2600);
DISPLAY 0.872340 (-925 2600);
PAINT AQUA (-925 2600);
DISPLAY INVISIBLE (-925 2600);
FORCEADD Q_CAP..1
(-750 2250);
FORCEPROP 1 LAST PART_NUMBER CH4104K1B00
J 0
(-700 2100);
DISPLAY 0.638298 (-700 2100);
DISPLAY INVISIBLE (-700 2100);
FORCEPROP 1 LAST VOLTAGE 25V
J 0
(-700 2250);
DISPLAY 0.638298 (-700 2250);
FORCEPROP 1 LAST PACK_TYPE 0402
J 0
(-700 2050);
DISPLAY 0.638298 (-700 2050);
FORCEPROP 1 LAST TOLERANCE 10%
J 0
(-700 2200);
DISPLAY 0.638298 (-700 2200);
FORCEPROP 1 LAST VALUE 0.1UF
J 0
(-700 2300);
DISPLAY 0.638298 (-700 2300);
FORCEPROP 1 LAST MATERIAL X7R
J 0
(-700 2150);
DISPLAY 0.638298 (-700 2150);
FORCEPROP 1 LAST $LOCATION C538
J 0
(-700 2350);
DISPLAY 0.978723 (-700 2350);
FORCEPROP 1 LASTPIN (-750 2350) $PN 1
J 0
(-740 2330);
DISPLAY 0.787234 (-740 2330);
FORCEPROP 1 LASTPIN (-750 2150) $PN 2
J 0
(-740 2130);
DISPLAY 0.787234 (-740 2130);
FORCEPROP 2 LAST CDS_LIB pure_quanta
J 0
(-750 2250);
PAINT MONO (-750 2250);
DISPLAY INVISIBLE (-750 2250);
FORCEPROP 1 LAST PATH I24
J 0
(-700 2400);
DISPLAY 0.978723 (-700 2400);
PAINT WHITE (-700 2400);
DISPLAY INVISIBLE (-700 2400);
FORCEPROP 2 LAST CDS_LOCATION C538
J 0
(-700 2450);
DISPLAY 1.021277 (-700 2450);
DISPLAY INVISIBLE (-700 2450);
FORCEPROP 2 LAST $SEC 1
J 0
(-700 2450);
DISPLAY 0.680851 (-700 2450);
PAINT MONO (-700 2450);
DISPLAY INVISIBLE (-700 2450);
FORCEPROP 2 LAST CDS_SEC 1
J 0
(-700 2450);
DISPLAY 1.021277 (-700 2450);
DISPLAY INVISIBLE (-700 2450);
FORCEADD Q_RES..1
(-875 3975);
FORCEPROP 1 LAST PART_NUMBER CS00002JB13
J 0
(-750 4000);
DISPLAY 0.319149 (-750 4000);
DISPLAY INVISIBLE (-750 4000);
FORCEPROP 1 LAST TOLERANCE 5%
J 0
(-700 3975);
DISPLAY 0.404255 (-700 3975);
FORCEPROP 1 LAST MATERIAL CHIP
J 0
(-625 3975);
DISPLAY 0.404255 (-625 3975);
FORCEPROP 1 LAST WATTAGE 1/16W
J 2
(-575 4025);
DISPLAY 0.319149 (-575 4025);
FORCEPROP 1 LAST PACK_TYPE 0402LF
J 0
(-750 4025);
DISPLAY 0.319149 (-750 4025);
FORCEPROP 1 LAST VALUE 0
J 2
(-725 3975);
DISPLAY 0.404255 (-725 3975);
FORCEPROP 1 LAST LOCATION R689
J 0
(-1075 3975);
DISPLAY 0.808511 (-1075 3975);
FORCEPROP 1 LASTPIN (-975 3975) $PN 1
J 0
(-963 3987);
DISPLAY 0.787234 (-963 3987);
PAINT MONO (-963 3987);
FORCEPROP 1 LASTPIN (-775 3975) $PN 2
J 0
(-813 3987);
DISPLAY 0.787234 (-813 3987);
PAINT MONO (-813 3987);
FORCEPROP 2 LAST CDS_LIB pure_quanta
J 0
(-875 3975);
DISPLAY INVISIBLE (-875 3975);
FORCEPROP 1 LAST PATH I25
J 0
(-925 4125);
DISPLAY 0.978723 (-925 4125);
PAINT WHITE (-925 4125);
DISPLAY INVISIBLE (-925 4125);
FORCEPROP 0 LAST $SEC 1
J 0
(-575 4050);
DISPLAY 0.680851 (-575 4050);
PAINT MONO (-575 4050);
DISPLAY INVISIBLE (-575 4050);
FORCEPROP 0 LAST CDS_SEC 1
J 0
(-575 4050);
DISPLAY 1.021277 (-575 4050);
DISPLAY INVISIBLE (-575 4050);
FORCEADD Q_RES..1
(-875 3925);
FORCEPROP 1 LAST PART_NUMBER CS03322FB03
J 0
(-925 3975);
DISPLAY 0.404255 (-925 3975);
DISPLAY INVISIBLE (-925 3975);
FORCEPROP 1 LAST VALUE 33.2
J 2
(-675 3925);
DISPLAY 0.404255 (-675 3925);
FORCEPROP 1 LAST TOLERANCE 1%
J 0
(-650 3925);
DISPLAY 0.404255 (-650 3925);
FORCEPROP 1 LAST PACK_TYPE 0402LF
J 0
(-575 3925);
DISPLAY 0.404255 (-575 3925);
FORCEPROP 1 LAST $LOCATION R690
J 0
(-1075 3925);
DISPLAY 0.787234 (-1075 3925);
FORCEPROP 1 LASTPIN (-975 3925) $PN 1
J 0
(-963 3937);
DISPLAY 0.787234 (-963 3937);
FORCEPROP 1 LASTPIN (-775 3925) $PN 2
J 0
(-813 3937);
DISPLAY 0.787234 (-813 3937);
FORCEPROP 1 LAST MATERIAL CHIP
J 0
(-925 4000);
DISPLAY 0.404255 (-925 4000);
DISPLAY INVISIBLE (-925 4000);
FORCEPROP 1 LAST WATTAGE 1/16W
J 2
(-700 4000);
DISPLAY 0.404255 (-700 4000);
DISPLAY INVISIBLE (-700 4000);
FORCEPROP 2 LAST CDS_LIB pure_quanta
J 0
(-875 3925);
PAINT MONO (-875 3925);
DISPLAY INVISIBLE (-875 3925);
FORCEPROP 1 LAST PATH I26
J 0
(-925 4075);
DISPLAY 0.978723 (-925 4075);
PAINT WHITE (-925 4075);
DISPLAY INVISIBLE (-925 4075);
FORCEPROP 2 LAST CDS_LOCATION R690
J 0
(-925 4125);
DISPLAY 1.021277 (-925 4125);
DISPLAY INVISIBLE (-925 4125);
FORCEPROP 2 LAST $SEC 1
J 0
(-925 4125);
DISPLAY 0.680851 (-925 4125);
PAINT MONO (-925 4125);
DISPLAY INVISIBLE (-925 4125);
FORCEPROP 2 LAST CDS_SEC 1
J 0
(-925 4125);
DISPLAY 1.021277 (-925 4125);
DISPLAY INVISIBLE (-925 4125);
FORCEADD OFFPAGE..3
R 2
(-3100 4225);
FORCEPROP 2 LAST $XR0 13 
J 0
(-3379 4225);
DISPLAY 0.638298 (-3379 4225);
PAINT MONO (-3379 4225);
FORCEPROP 1 LAST COMMENT_BODY TRUE
J 2
(-3050 4125);
DISPLAY 0.872340 (-3050 4125);
PAINT GREEN (-3050 4125);
DISPLAY INVISIBLE (-3050 4125);
FORCEPROP 1 LAST OFFPAGE TRUE
J 2
(-3425 4100);
DISPLAY 0.872340 (-3425 4100);
DISPLAY INVISIBLE (-3425 4100);
FORCEPROP 2 LAST CDS_LIB standard
J 0
(-3100 4225);
PAINT MONO (-3100 4225);
DISPLAY INVISIBLE (-3100 4225);
FORCEPROP 2 LAST PATH I27
J 0
(-3375 4275);
DISPLAY 1.021277 (-3375 4275);
DISPLAY INVISIBLE (-3375 4275);
FORCEADD OFFPAGE..1
(-3100 4275);
FORCEPROP 2 LAST $XR0 13 
J 0
(-3351 4275);
DISPLAY 0.638298 (-3351 4275);
PAINT MONO (-3351 4275);
FORCEPROP 1 LAST COMMENT_BODY TRUE
J 0
(-2975 4175);
DISPLAY 0.872340 (-2975 4175);
PAINT GREEN (-2975 4175);
DISPLAY INVISIBLE (-2975 4175);
FORCEPROP 1 LAST OFFPAGE TRUE
J 0
(-2775 4150);
DISPLAY 0.872340 (-2775 4150);
PAINT GREEN (-2775 4150);
DISPLAY INVISIBLE (-2775 4150);
FORCEPROP 2 LAST CDS_LIB standard
J 0
(-3100 4275);
PAINT MONO (-3100 4275);
DISPLAY INVISIBLE (-3100 4275);
FORCEPROP 2 LAST PATH I28
J 0
(-3350 4325);
DISPLAY 1.021277 (-3350 4325);
DISPLAY INVISIBLE (-3350 4325);
FORCEADD Q_RES..2
(-1975 4600);
FORCEPROP 1 LAST PART_NUMBER CS14992FB06
J 0
(-1935 4425);
DISPLAY 0.638298 (-1935 4425);
DISPLAY INVISIBLE (-1935 4425);
FORCEPROP 1 LAST WATTAGE 1/16W
J 0
(-1935 4575);
DISPLAY 0.638298 (-1935 4575);
FORCEPROP 1 LAST VALUE 499
J 0
(-1930 4675);
DISPLAY 0.638298 (-1930 4675);
FORCEPROP 1 LAST TOLERANCE 1%
J 0
(-1930 4625);
DISPLAY 0.638298 (-1930 4625);
FORCEPROP 1 LAST MATERIAL CHIP
J 0
(-1935 4525);
DISPLAY 0.638298 (-1935 4525);
FORCEPROP 1 LAST PACK_TYPE 0402LF
J 0
(-1935 4475);
DISPLAY 0.638298 (-1935 4475);
FORCEPROP 1 LAST $LOCATION R679
J 0
(-1930 4725);
DISPLAY 0.978723 (-1930 4725);
FORCEPROP 1 LASTPIN (-1975 4700) $PN 1
J 0
(-1970 4662);
DISPLAY 0.787234 (-1970 4662);
FORCEPROP 1 LASTPIN (-1975 4500) $PN 2
J 0
(-1970 4510);
DISPLAY 0.787234 (-1970 4510);
FORCEPROP 2 LAST CDS_LIB pure_quanta
J 0
(-1975 4600);
PAINT MONO (-1975 4600);
DISPLAY INVISIBLE (-1975 4600);
FORCEPROP 1 LAST PATH I29
J 0
(-1925 4775);
DISPLAY 0.978723 (-1925 4775);
PAINT WHITE (-1925 4775);
DISPLAY INVISIBLE (-1925 4775);
FORCEPROP 2 LAST CDS_LOCATION R679
J 0
(-1925 4825);
DISPLAY 1.021277 (-1925 4825);
DISPLAY INVISIBLE (-1925 4825);
FORCEPROP 2 LAST $SEC 1
J 0
(-1925 4825);
DISPLAY 0.680851 (-1925 4825);
PAINT MONO (-1925 4825);
DISPLAY INVISIBLE (-1925 4825);
FORCEPROP 2 LAST CDS_SEC 1
J 0
(-1925 4825);
DISPLAY 1.021277 (-1925 4825);
DISPLAY INVISIBLE (-1925 4825);
FORCEADD Q_RES..2
(-1725 4600);
FORCEPROP 1 LAST PART_NUMBER CS14992FB06
J 0
(-1685 4425);
DISPLAY 0.638298 (-1685 4425);
DISPLAY INVISIBLE (-1685 4425);
FORCEPROP 1 LAST WATTAGE 1/16W
J 0
(-1685 4575);
DISPLAY 0.638298 (-1685 4575);
FORCEPROP 1 LAST TOLERANCE 1%
J 0
(-1680 4625);
DISPLAY 0.638298 (-1680 4625);
FORCEPROP 1 LAST MATERIAL CHIP
J 0
(-1685 4525);
DISPLAY 0.638298 (-1685 4525);
FORCEPROP 1 LAST PACK_TYPE 0402LF
J 0
(-1685 4475);
DISPLAY 0.638298 (-1685 4475);
FORCEPROP 1 LAST VALUE 499
J 0
(-1680 4675);
DISPLAY 0.638298 (-1680 4675);
FORCEPROP 1 LAST $LOCATION R680
J 0
(-1680 4725);
DISPLAY 0.978723 (-1680 4725);
FORCEPROP 1 LASTPIN (-1725 4700) $PN 1
J 0
(-1720 4662);
DISPLAY 0.787234 (-1720 4662);
FORCEPROP 1 LASTPIN (-1725 4500) $PN 2
J 0
(-1720 4510);
DISPLAY 0.787234 (-1720 4510);
FORCEPROP 2 LAST CDS_LIB pure_quanta
J 0
(-1725 4600);
PAINT MONO (-1725 4600);
DISPLAY INVISIBLE (-1725 4600);
FORCEPROP 1 LAST PATH I30
J 0
(-1675 4775);
DISPLAY 0.978723 (-1675 4775);
PAINT WHITE (-1675 4775);
DISPLAY INVISIBLE (-1675 4775);
FORCEPROP 2 LAST CDS_LOCATION R680
J 0
(-1675 4825);
DISPLAY 1.021277 (-1675 4825);
DISPLAY INVISIBLE (-1675 4825);
FORCEPROP 2 LAST $SEC 1
J 0
(-1675 4825);
DISPLAY 0.680851 (-1675 4825);
PAINT MONO (-1675 4825);
DISPLAY INVISIBLE (-1675 4825);
FORCEPROP 2 LAST CDS_SEC 1
J 0
(-1675 4825);
DISPLAY 1.021277 (-1675 4825);
DISPLAY INVISIBLE (-1675 4825);
FORCEADD UNIVERSAL_POWER..1
(-1975 4975);
FORCEPROP 3 LASTPIN (-1975 4925) SIG_NAME PVNN_TERM_CPU0\g
J 0
(-1965 4935);
DISPLAY 0.659574 (-1965 4935);
PAINT MONO (-1965 4935);
DISPLAY INVISIBLE (-1965 4935);
FORCEPROP 1 LAST HDL_POWER PVNN_TERM_CPU0
J 1
(-1975 5025);
DISPLAY 0.702128 (-1975 5025);
PAINT GREEN (-1975 5025);
FORCEPROP 2 LAST CDS_LIB logical_power
J 0
(-1975 4975);
PAINT MONO (-1975 4975);
DISPLAY INVISIBLE (-1975 4975);
FORCEPROP 1 LAST PATH I31
J 0
(-1925 5000);
DISPLAY 0.872340 (-1925 5000);
PAINT AQUA (-1925 5000);
DISPLAY INVISIBLE (-1925 5000);
FORCEADD Q_RES..2
(-1475 4600);
FORCEPROP 1 LAST PART_NUMBER CS14992FB06
J 0
(-1435 4425);
DISPLAY 0.638298 (-1435 4425);
DISPLAY INVISIBLE (-1435 4425);
FORCEPROP 1 LAST MATERIAL CHIP
J 0
(-1435 4525);
DISPLAY 0.638298 (-1435 4525);
FORCEPROP 1 LAST WATTAGE 1/16W
J 0
(-1435 4575);
DISPLAY 0.638298 (-1435 4575);
FORCEPROP 1 LAST PACK_TYPE 0402LF
J 0
(-1435 4475);
DISPLAY 0.638298 (-1435 4475);
FORCEPROP 1 LAST VALUE 499
J 0
(-1430 4675);
DISPLAY 0.638298 (-1430 4675);
FORCEPROP 1 LAST TOLERANCE 1%
J 0
(-1430 4625);
DISPLAY 0.638298 (-1430 4625);
FORCEPROP 1 LAST $LOCATION R681
J 0
(-1430 4725);
DISPLAY 0.978723 (-1430 4725);
FORCEPROP 1 LASTPIN (-1475 4700) $PN 1
J 0
(-1470 4662);
DISPLAY 0.787234 (-1470 4662);
FORCEPROP 1 LASTPIN (-1475 4500) $PN 2
J 0
(-1470 4510);
DISPLAY 0.787234 (-1470 4510);
FORCEPROP 2 LAST CDS_LIB pure_quanta
J 0
(-1475 4600);
PAINT MONO (-1475 4600);
DISPLAY INVISIBLE (-1475 4600);
FORCEPROP 1 LAST PATH I32
J 0
(-1425 4775);
DISPLAY 0.978723 (-1425 4775);
PAINT WHITE (-1425 4775);
DISPLAY INVISIBLE (-1425 4775);
FORCEPROP 2 LAST CDS_LOCATION R681
J 0
(-1425 4825);
DISPLAY 1.021277 (-1425 4825);
DISPLAY INVISIBLE (-1425 4825);
FORCEPROP 2 LAST $SEC 1
J 0
(-1425 4825);
DISPLAY 0.680851 (-1425 4825);
PAINT MONO (-1425 4825);
DISPLAY INVISIBLE (-1425 4825);
FORCEPROP 2 LAST CDS_SEC 1
J 0
(-1425 4825);
DISPLAY 1.021277 (-1425 4825);
DISPLAY INVISIBLE (-1425 4825);
FORCEADD Q_RES..2
(-1225 4600);
FORCEPROP 1 LAST PART_NUMBER CS14992FB06
J 0
(-1185 4425);
DISPLAY 0.638298 (-1185 4425);
DISPLAY INVISIBLE (-1185 4425);
FORCEPROP 1 LAST PACK_TYPE 0402LF
J 0
(-1185 4475);
DISPLAY 0.638298 (-1185 4475);
FORCEPROP 1 LAST VALUE 499
J 0
(-1180 4675);
DISPLAY 0.638298 (-1180 4675);
FORCEPROP 1 LAST MATERIAL CHIP
J 0
(-1185 4525);
DISPLAY 0.638298 (-1185 4525);
FORCEPROP 1 LAST TOLERANCE 1%
J 0
(-1180 4625);
DISPLAY 0.638298 (-1180 4625);
FORCEPROP 1 LAST WATTAGE 1/16W
J 0
(-1185 4575);
DISPLAY 0.638298 (-1185 4575);
FORCEPROP 1 LAST $LOCATION R686
J 0
(-1180 4725);
DISPLAY 0.978723 (-1180 4725);
FORCEPROP 1 LASTPIN (-1225 4700) $PN 1
J 0
(-1220 4662);
DISPLAY 0.787234 (-1220 4662);
FORCEPROP 1 LASTPIN (-1225 4500) $PN 2
J 0
(-1220 4510);
DISPLAY 0.787234 (-1220 4510);
FORCEPROP 2 LAST CDS_LIB pure_quanta
J 0
(-1225 4600);
PAINT MONO (-1225 4600);
DISPLAY INVISIBLE (-1225 4600);
FORCEPROP 1 LAST PATH I33
J 0
(-1175 4775);
DISPLAY 0.978723 (-1175 4775);
PAINT WHITE (-1175 4775);
DISPLAY INVISIBLE (-1175 4775);
FORCEPROP 2 LAST CDS_LOCATION R686
J 0
(-1175 4825);
DISPLAY 1.021277 (-1175 4825);
DISPLAY INVISIBLE (-1175 4825);
FORCEPROP 2 LAST $SEC 1
J 0
(-1175 4825);
DISPLAY 0.680851 (-1175 4825);
PAINT MONO (-1175 4825);
DISPLAY INVISIBLE (-1175 4825);
FORCEPROP 2 LAST CDS_SEC 1
J 0
(-1175 4825);
DISPLAY 1.021277 (-1175 4825);
DISPLAY INVISIBLE (-1175 4825);
FORCEADD Q_RES..1
(-875 4275);
FORCEPROP 1 LAST PART_NUMBER CS00002JB13
J 0
(-750 4300);
DISPLAY 0.319149 (-750 4300);
DISPLAY INVISIBLE (-750 4300);
FORCEPROP 1 LAST TOLERANCE 5%
J 0
(-700 4275);
DISPLAY 0.404255 (-700 4275);
FORCEPROP 1 LAST MATERIAL CHIP
J 0
(-625 4275);
DISPLAY 0.404255 (-625 4275);
FORCEPROP 1 LAST WATTAGE 1/16W
J 2
(-575 4325);
DISPLAY 0.319149 (-575 4325);
FORCEPROP 1 LAST PACK_TYPE 0402LF
J 0
(-750 4325);
DISPLAY 0.319149 (-750 4325);
FORCEPROP 1 LAST VALUE 0
J 2
(-725 4275);
DISPLAY 0.404255 (-725 4275);
FORCEPROP 1 LAST LOCATION R687
J 0
(-1075 4275);
DISPLAY 0.787234 (-1075 4275);
FORCEPROP 1 LASTPIN (-975 4275) $PN 1
J 0
(-963 4287);
DISPLAY 0.787234 (-963 4287);
PAINT MONO (-963 4287);
FORCEPROP 1 LASTPIN (-775 4275) $PN 2
J 0
(-813 4287);
DISPLAY 0.787234 (-813 4287);
PAINT MONO (-813 4287);
FORCEPROP 2 LAST CDS_LIB pure_quanta
J 0
(-875 4275);
DISPLAY INVISIBLE (-875 4275);
FORCEPROP 1 LAST PATH I34
J 0
(-925 4425);
DISPLAY 0.978723 (-925 4425);
PAINT WHITE (-925 4425);
DISPLAY INVISIBLE (-925 4425);
FORCEPROP 0 LAST $SEC 1
J 0
(-575 4350);
DISPLAY 0.680851 (-575 4350);
PAINT MONO (-575 4350);
DISPLAY INVISIBLE (-575 4350);
FORCEPROP 0 LAST CDS_SEC 1
J 0
(-575 4350);
DISPLAY 1.021277 (-575 4350);
DISPLAY INVISIBLE (-575 4350);
FORCEADD Q_RES..1
(-875 4225);
FORCEPROP 1 LAST PART_NUMBER CS03322FB03
J 0
(-925 4275);
DISPLAY 0.404255 (-925 4275);
DISPLAY INVISIBLE (-925 4275);
FORCEPROP 1 LAST PACK_TYPE 0402LF
J 0
(-575 4225);
DISPLAY 0.404255 (-575 4225);
FORCEPROP 1 LAST VALUE 33.2
J 2
(-675 4225);
DISPLAY 0.404255 (-675 4225);
FORCEPROP 1 LAST TOLERANCE 1%
J 0
(-650 4225);
DISPLAY 0.404255 (-650 4225);
FORCEPROP 1 LAST $LOCATION R688
J 0
(-1075 4225);
DISPLAY 0.787234 (-1075 4225);
FORCEPROP 1 LASTPIN (-975 4225) $PN 1
J 0
(-963 4237);
DISPLAY 0.787234 (-963 4237);
FORCEPROP 1 LASTPIN (-775 4225) $PN 2
J 0
(-813 4237);
DISPLAY 0.787234 (-813 4237);
FORCEPROP 1 LAST MATERIAL CHIP
J 0
(-925 4300);
DISPLAY 0.404255 (-925 4300);
DISPLAY INVISIBLE (-925 4300);
FORCEPROP 1 LAST WATTAGE 1/16W
J 2
(-700 4300);
DISPLAY 0.404255 (-700 4300);
DISPLAY INVISIBLE (-700 4300);
FORCEPROP 2 LAST CDS_LIB pure_quanta
J 0
(-875 4225);
PAINT MONO (-875 4225);
DISPLAY INVISIBLE (-875 4225);
FORCEPROP 1 LAST PATH I35
J 0
(-925 4375);
DISPLAY 0.978723 (-925 4375);
PAINT WHITE (-925 4375);
DISPLAY INVISIBLE (-925 4375);
FORCEPROP 2 LAST CDS_LOCATION R688
J 0
(-925 4425);
DISPLAY 1.021277 (-925 4425);
DISPLAY INVISIBLE (-925 4425);
FORCEPROP 2 LAST $SEC 1
J 0
(-925 4425);
DISPLAY 0.680851 (-925 4425);
PAINT MONO (-925 4425);
DISPLAY INVISIBLE (-925 4425);
FORCEPROP 2 LAST CDS_SEC 1
J 0
(-925 4425);
DISPLAY 1.021277 (-925 4425);
DISPLAY INVISIBLE (-925 4425);
FORCEADD OFFPAGE..5
(700 725);
FORCEPROP 2 LAST $XR1 230 
J 0
(295 725);
DISPLAY 0.638298 (295 725);
PAINT MONO (295 725);
FORCEPROP 2 LAST $XR0 229 
J 0
(415 725);
DISPLAY 0.638298 (415 725);
PAINT MONO (415 725);
FORCEPROP 1 LAST COMMENT_BODY TRUE
J 0
(800 650);
DISPLAY 0.872340 (800 650);
PAINT PEACH (800 650);
DISPLAY INVISIBLE (800 650);
FORCEPROP 1 LAST OFFPAGE TRUE
J 0
(1025 600);
DISPLAY 0.872340 (1025 600);
PAINT GREEN (1025 600);
DISPLAY INVISIBLE (1025 600);
FORCEPROP 2 LAST CDS_LIB standard
J 0
(700 725);
PAINT MONO (700 725);
DISPLAY INVISIBLE (700 725);
FORCEPROP 2 LAST PATH I36
J 0
(425 775);
DISPLAY 1.021277 (425 775);
DISPLAY INVISIBLE (425 775);
FORCEADD Q_RES..1
(750 1475);
FORCEPROP 1 LAST PART_NUMBER CS03322FB03
J 0
(700 1525);
DISPLAY 0.404255 (700 1525);
DISPLAY INVISIBLE (700 1525);
FORCEPROP 1 LAST VALUE 33.2
J 2
(900 1475);
DISPLAY 0.510638 (900 1475);
FORCEPROP 1 LAST TOLERANCE 1%
J 0
(925 1475);
DISPLAY 0.510638 (925 1475);
FORCEPROP 1 LAST $LOCATION R694
J 0
(550 1475);
DISPLAY 0.638298 (550 1475);
FORCEPROP 1 LASTPIN (650 1475) $PN 1
J 0
(662 1487);
DISPLAY 0.787234 (662 1487);
FORCEPROP 1 LASTPIN (850 1475) $PN 2
J 0
(812 1487);
DISPLAY 0.787234 (812 1487);
FORCEPROP 1 LAST PACK_TYPE 0402LF
J 0
(1000 1475);
DISPLAY 0.510638 (1000 1475);
DISPLAY INVISIBLE (1000 1475);
FORCEPROP 1 LAST MATERIAL CHIP
J 0
(700 1550);
DISPLAY 0.404255 (700 1550);
DISPLAY INVISIBLE (700 1550);
FORCEPROP 1 LAST WATTAGE 1/16W
J 2
(925 1550);
DISPLAY 0.404255 (925 1550);
DISPLAY INVISIBLE (925 1550);
FORCEPROP 2 LAST CDS_LIB pure_quanta
J 0
(750 1475);
PAINT MONO (750 1475);
DISPLAY INVISIBLE (750 1475);
FORCEPROP 1 LAST PATH I37
J 0
(700 1625);
DISPLAY 0.978723 (700 1625);
PAINT WHITE (700 1625);
DISPLAY INVISIBLE (700 1625);
FORCEPROP 2 LAST CDS_LOCATION R694
J 0
(700 1675);
DISPLAY 1.021277 (700 1675);
DISPLAY INVISIBLE (700 1675);
FORCEPROP 2 LAST $SEC 1
J 0
(700 1675);
DISPLAY 0.680851 (700 1675);
PAINT MONO (700 1675);
DISPLAY INVISIBLE (700 1675);
FORCEPROP 2 LAST CDS_SEC 1
J 0
(700 1675);
DISPLAY 1.021277 (700 1675);
DISPLAY INVISIBLE (700 1675);
FORCEADD Q_RES..1
(750 1625);
FORCEPROP 1 LAST PART_NUMBER CS00002JB13
J 0
(700 1675);
DISPLAY 0.404255 (700 1675);
DISPLAY INVISIBLE (700 1675);
FORCEPROP 1 LAST VALUE 0
J 2
(900 1625);
DISPLAY 0.510638 (900 1625);
FORCEPROP 1 LAST TOLERANCE 5%
J 0
(925 1625);
DISPLAY 0.510638 (925 1625);
FORCEPROP 1 LAST $LOCATION R693
J 0
(550 1625);
DISPLAY 0.638298 (550 1625);
FORCEPROP 1 LASTPIN (650 1625) $PN 1
J 0
(662 1637);
DISPLAY 0.787234 (662 1637);
FORCEPROP 1 LASTPIN (850 1625) $PN 2
J 0
(812 1637);
DISPLAY 0.787234 (812 1637);
FORCEPROP 1 LAST MATERIAL CHIP
J 0
(700 1700);
DISPLAY 0.404255 (700 1700);
DISPLAY INVISIBLE (700 1700);
FORCEPROP 1 LAST WATTAGE 1/16W
J 2
(925 1700);
DISPLAY 0.404255 (925 1700);
DISPLAY INVISIBLE (925 1700);
FORCEPROP 2 LAST CDS_LIB pure_quanta
J 0
(750 1625);
PAINT MONO (750 1625);
DISPLAY INVISIBLE (750 1625);
FORCEPROP 1 LAST PACK_TYPE 0402LF
J 0
(1000 1625);
DISPLAY 0.510638 (1000 1625);
DISPLAY INVISIBLE (1000 1625);
FORCEPROP 1 LAST PATH I38
J 0
(700 1775);
DISPLAY 0.978723 (700 1775);
PAINT WHITE (700 1775);
DISPLAY INVISIBLE (700 1775);
FORCEPROP 2 LAST CDS_LOCATION R693
J 0
(700 1825);
DISPLAY 1.021277 (700 1825);
DISPLAY INVISIBLE (700 1825);
FORCEPROP 2 LAST $SEC 1
J 0
(700 1825);
DISPLAY 0.680851 (700 1825);
PAINT MONO (700 1825);
DISPLAY INVISIBLE (700 1825);
FORCEPROP 2 LAST CDS_SEC 1
J 0
(700 1825);
DISPLAY 1.021277 (700 1825);
DISPLAY INVISIBLE (700 1825);
FORCEADD Q_RES..1
(750 1925);
FORCEPROP 1 LAST PART_NUMBER CS00002JB13
J 0
(700 1975);
DISPLAY 0.404255 (700 1975);
DISPLAY INVISIBLE (700 1975);
FORCEPROP 1 LAST TOLERANCE 5%
J 0
(925 1925);
DISPLAY 0.510638 (925 1925);
FORCEPROP 1 LAST MATERIAL CHIP
J 0
(700 2000);
DISPLAY 0.404255 (700 2000);
FORCEPROP 1 LAST WATTAGE 1/16W
J 2
(925 2000);
DISPLAY 0.404255 (925 2000);
FORCEPROP 1 LAST VALUE 0
J 2
(900 1925);
DISPLAY 0.510638 (900 1925);
FORCEPROP 1 LAST PACK_TYPE 0402LF
J 0
(700 2025);
DISPLAY 0.404255 (700 2025);
FORCEPROP 1 LAST $LOCATION R691
J 0
(550 1925);
DISPLAY 0.638298 (550 1925);
FORCEPROP 1 LASTPIN (650 1925) $PN 1
J 0
(662 1937);
DISPLAY 0.787234 (662 1937);
FORCEPROP 1 LASTPIN (850 1925) $PN 2
J 0
(812 1937);
DISPLAY 0.787234 (812 1937);
FORCEPROP 2 LAST CDS_LIB pure_quanta
J 0
(750 1925);
PAINT MONO (750 1925);
DISPLAY INVISIBLE (750 1925);
FORCEPROP 1 LAST PATH I39
J 0
(700 2075);
DISPLAY 0.978723 (700 2075);
PAINT WHITE (700 2075);
DISPLAY INVISIBLE (700 2075);
FORCEPROP 2 LAST CDS_LOCATION R691
J 0
(700 2125);
DISPLAY 1.021277 (700 2125);
DISPLAY INVISIBLE (700 2125);
FORCEPROP 2 LAST $SEC 1
J 0
(700 2125);
DISPLAY 0.680851 (700 2125);
PAINT MONO (700 2125);
DISPLAY INVISIBLE (700 2125);
FORCEPROP 2 LAST CDS_SEC 1
J 0
(700 2125);
DISPLAY 1.021277 (700 2125);
DISPLAY INVISIBLE (700 2125);
FORCEADD OFFPAGE..3
R 2
(-3100 1525);
FORCEPROP 2 LAST $XR0 241 
J 0
(-3410 1525);
DISPLAY 0.638298 (-3410 1525);
PAINT MONO (-3410 1525);
FORCEPROP 1 LAST COMMENT_BODY TRUE
J 2
(-3050 1425);
DISPLAY 0.872340 (-3050 1425);
PAINT GREEN (-3050 1425);
DISPLAY INVISIBLE (-3050 1425);
FORCEPROP 1 LAST OFFPAGE TRUE
J 2
(-3425 1400);
DISPLAY 0.872340 (-3425 1400);
DISPLAY INVISIBLE (-3425 1400);
FORCEPROP 2 LAST CDS_LIB standard
J 0
(-3100 1525);
PAINT MONO (-3100 1525);
DISPLAY INVISIBLE (-3100 1525);
FORCEPROP 2 LAST PATH I4
J 0
(-3400 1575);
DISPLAY 1.021277 (-3400 1575);
DISPLAY INVISIBLE (-3400 1575);
FORCEADD Q_RES..1
(750 1775);
FORCEPROP 1 LAST PART_NUMBER CS03322FB03
J 0
(700 1825);
DISPLAY 0.404255 (700 1825);
DISPLAY INVISIBLE (700 1825);
FORCEPROP 1 LAST TOLERANCE 1%
J 0
(975 1775);
DISPLAY 0.510638 (975 1775);
FORCEPROP 1 LAST VALUE 33.2
J 2
(950 1775);
DISPLAY 0.510638 (950 1775);
FORCEPROP 1 LAST $LOCATION R692
J 0
(550 1775);
DISPLAY 0.638298 (550 1775);
FORCEPROP 1 LASTPIN (650 1775) $PN 1
J 0
(662 1787);
DISPLAY 0.787234 (662 1787);
FORCEPROP 1 LASTPIN (850 1775) $PN 2
J 0
(812 1787);
DISPLAY 0.787234 (812 1787);
FORCEPROP 1 LAST PACK_TYPE 0402LF
J 0
(1000 1775);
DISPLAY 0.510638 (1000 1775);
DISPLAY INVISIBLE (1000 1775);
FORCEPROP 2 LAST CDS_LIB pure_quanta
J 0
(750 1775);
PAINT MONO (750 1775);
DISPLAY INVISIBLE (750 1775);
FORCEPROP 1 LAST WATTAGE 1/16W
J 2
(925 1850);
DISPLAY 0.404255 (925 1850);
DISPLAY INVISIBLE (925 1850);
FORCEPROP 1 LAST MATERIAL CHIP
J 0
(700 1850);
DISPLAY 0.404255 (700 1850);
DISPLAY INVISIBLE (700 1850);
FORCEPROP 1 LAST PATH I40
J 0
(700 1925);
DISPLAY 0.978723 (700 1925);
PAINT WHITE (700 1925);
DISPLAY INVISIBLE (700 1925);
FORCEPROP 2 LAST CDS_LOCATION R692
J 0
(700 1975);
DISPLAY 1.021277 (700 1975);
DISPLAY INVISIBLE (700 1975);
FORCEPROP 2 LAST $SEC 1
J 0
(700 1975);
DISPLAY 0.680851 (700 1975);
PAINT MONO (700 1975);
DISPLAY INVISIBLE (700 1975);
FORCEPROP 2 LAST CDS_SEC 1
J 0
(700 1975);
DISPLAY 1.021277 (700 1975);
DISPLAY INVISIBLE (700 1975);
FORCEADD UNIVERSAL_GND..1
(1600 300);
FORCEPROP 3 LASTPIN (1600 350) SIG_NAME GND\g
J 0
(1610 360);
DISPLAY 0.659574 (1610 360);
PAINT MONO (1610 360);
DISPLAY INVISIBLE (1610 360);
FORCEPROP 1 LAST HDL_POWER GND
J 1
(1625 225);
DISPLAY 0.872340 (1625 225);
PAINT GREEN (1625 225);
DISPLAY INVISIBLE (1625 225);
FORCEPROP 2 LAST ROOM IO_SLOT
J 1
(1375 375);
DISPLAY 0.744681 (1375 375);
DISPLAY INVISIBLE (1375 375);
FORCEPROP 2 LAST CDS_LIB logical_power
J 0
(1600 300);
PAINT MONO (1600 300);
DISPLAY INVISIBLE (1600 300);
FORCEPROP 1 LAST PATH I41
J 0
(1675 300);
DISPLAY 0.872340 (1675 300);
PAINT AQUA (1675 300);
DISPLAY INVISIBLE (1675 300);
FORCEADD Q_RES..2
(1600 525);
FORCEPROP 1 LAST PART_NUMBER CS31002FB08
J 0
(1640 400);
DISPLAY 0.787234 (1640 400);
DISPLAY INVISIBLE (1640 400);
FORCEPROP 1 LAST VALUE 10K
J 0
(1645 600);
DISPLAY 0.787234 (1645 600);
FORCEPROP 1 LAST TOLERANCE 1%
J 0
(1645 550);
DISPLAY 0.787234 (1645 550);
FORCEPROP 1 LAST MATERIAL CHIP
J 0
(1640 450);
DISPLAY 0.787234 (1640 450);
FORCEPROP 1 LAST PACK_TYPE 0402LF
J 0
(1640 350);
DISPLAY 0.787234 (1640 350);
FORCEPROP 1 LAST WATTAGE 1/16W
J 0
(1640 500);
DISPLAY 0.787234 (1640 500);
FORCEPROP 1 LAST $LOCATION R318
J 0
(1645 650);
DISPLAY 0.978723 (1645 650);
FORCEPROP 1 LASTPIN (1600 625) $PN 1
J 0
(1605 587);
DISPLAY 0.787234 (1605 587);
FORCEPROP 1 LASTPIN (1600 425) $PN 2
J 0
(1605 435);
DISPLAY 0.787234 (1605 435);
FORCEPROP 2 LAST CDS_LIB pure_quanta
J 0
(1600 525);
PAINT MONO (1600 525);
DISPLAY INVISIBLE (1600 525);
FORCEPROP 1 LAST PATH I42
J 0
(1650 700);
DISPLAY 0.978723 (1650 700);
PAINT WHITE (1650 700);
DISPLAY INVISIBLE (1650 700);
FORCEPROP 1 LAST $LOCATION R318
J 0
(1650 750);
DISPLAY 1.021277 (1650 750);
DISPLAY INVISIBLE (1650 750);
FORCEPROP 2 LAST CDS_LOCATION R318
J 0
(1650 750);
DISPLAY 1.021277 (1650 750);
DISPLAY INVISIBLE (1650 750);
FORCEPROP 2 LAST $SEC 1
J 0
(1650 750);
DISPLAY 0.680851 (1650 750);
PAINT MONO (1650 750);
DISPLAY INVISIBLE (1650 750);
FORCEPROP 2 LAST CDS_SEC 1
J 0
(1650 750);
DISPLAY 1.021277 (1650 750);
DISPLAY INVISIBLE (1650 750);
FORCEADD Q_RES..2
(1600 950);
FORCEPROP 1 LAST PART_NUMBER CS21002FB06
J 0
(1640 825);
DISPLAY 0.638298 (1640 825);
DISPLAY INVISIBLE (1640 825);
FORCEPROP 1 LAST TOLERANCE 1%
J 0
(1645 975);
DISPLAY 0.787234 (1645 975);
FORCEPROP 1 LAST WATTAGE 1/16W
J 0
(1640 925);
DISPLAY 0.787234 (1640 925);
FORCEPROP 1 LAST MATERIAL EMPTY
J 0
(1640 875);
DISPLAY 0.787234 (1640 875);
FORCEPROP 1 LAST VALUE 1K
J 0
(1645 1025);
DISPLAY 0.787234 (1645 1025);
FORCEPROP 1 LAST PACK_TYPE 0402LF
J 0
(1640 775);
DISPLAY 0.787234 (1640 775);
FORCEPROP 1 LAST $LOCATION R87
J 0
(1645 1075);
DISPLAY 0.978723 (1645 1075);
FORCEPROP 1 LASTPIN (1600 1050) $PN 1
J 0
(1605 1012);
DISPLAY 0.787234 (1605 1012);
FORCEPROP 1 LASTPIN (1600 850) $PN 2
J 0
(1605 860);
DISPLAY 0.787234 (1605 860);
FORCEPROP 2 LAST CDS_LIB pure_quanta
J 0
(1600 950);
PAINT MONO (1600 950);
DISPLAY INVISIBLE (1600 950);
FORCEPROP 1 LAST PATH I43
J 0
(1650 1125);
DISPLAY 0.978723 (1650 1125);
PAINT WHITE (1650 1125);
DISPLAY INVISIBLE (1650 1125);
FORCEPROP 1 LAST $LOCATION R87
J 0
(1650 1175);
DISPLAY 1.021277 (1650 1175);
DISPLAY INVISIBLE (1650 1175);
FORCEPROP 2 LAST CDS_LOCATION R87
J 0
(1650 1175);
DISPLAY 1.021277 (1650 1175);
DISPLAY INVISIBLE (1650 1175);
FORCEPROP 2 LAST $SEC 1
J 0
(1650 1175);
DISPLAY 0.680851 (1650 1175);
PAINT MONO (1650 1175);
DISPLAY INVISIBLE (1650 1175);
FORCEPROP 2 LAST CDS_SEC 1
J 0
(1650 1175);
DISPLAY 1.021277 (1650 1175);
DISPLAY INVISIBLE (1650 1175);
FORCEADD UNIVERSAL_POWER..1
(1600 1200);
FORCEPROP 3 LASTPIN (1600 1150) SIG_NAME P3V3_AUX\g
J 0
(1610 1160);
DISPLAY 0.659574 (1610 1160);
PAINT MONO (1610 1160);
DISPLAY INVISIBLE (1610 1160);
FORCEPROP 1 LAST HDL_POWER P3V3_AUX
J 1
(1600 1250);
DISPLAY 0.872340 (1600 1250);
PAINT GREEN (1600 1250);
FORCEPROP 2 LAST CDS_LIB logical_power
J 0
(1600 1200);
PAINT MONO (1600 1200);
DISPLAY INVISIBLE (1600 1200);
FORCEPROP 1 LAST PATH I44
J 0
(1650 1225);
DISPLAY 0.872340 (1650 1225);
PAINT AQUA (1650 1225);
DISPLAY INVISIBLE (1650 1225);
FORCEADD OFFPAGE..3
(875 3925);
FORCEPROP 2 LAST $XR0 229 
J 0
(1089 3925);
DISPLAY 0.638298 (1089 3925);
PAINT MONO (1089 3925);
FORCEPROP 1 LAST COMMENT_BODY TRUE
J 0
(825 3825);
DISPLAY 0.872340 (825 3825);
PAINT GREEN (825 3825);
DISPLAY INVISIBLE (825 3825);
FORCEPROP 1 LAST OFFPAGE TRUE
J 0
(1200 3800);
DISPLAY 0.872340 (1200 3800);
PAINT GREEN (1200 3800);
DISPLAY INVISIBLE (1200 3800);
FORCEPROP 2 LAST CDS_LIB standard
J 0
(875 3925);
PAINT MONO (875 3925);
DISPLAY INVISIBLE (875 3925);
FORCEPROP 2 LAST PATH I45
J 0
(1100 3975);
DISPLAY 1.021277 (1100 3975);
DISPLAY INVISIBLE (1100 3975);
FORCEADD OFFPAGE..2
(875 3975);
FORCEPROP 2 LAST $XR0 229 
J 0
(1064 3975);
DISPLAY 0.638298 (1064 3975);
PAINT MONO (1064 3975);
FORCEPROP 1 LAST COMMENT_BODY TRUE
J 0
(830 3880);
DISPLAY 0.872340 (830 3880);
PAINT GREEN (830 3880);
DISPLAY INVISIBLE (830 3880);
FORCEPROP 1 LAST OFFPAGE TRUE
J 0
(1200 3850);
DISPLAY 0.872340 (1200 3850);
PAINT GREEN (1200 3850);
DISPLAY INVISIBLE (1200 3850);
FORCEPROP 2 LAST CDS_LIB standard
J 0
(875 3975);
PAINT MONO (875 3975);
DISPLAY INVISIBLE (875 3975);
FORCEPROP 2 LAST PATH I46
J 0
(1075 4025);
DISPLAY 1.021277 (1075 4025);
DISPLAY INVISIBLE (1075 4025);
FORCEADD OFFPAGE..3
(2100 1475);
FORCEPROP 2 LAST $XR0 90 
J 0
(2314 1475);
DISPLAY 0.638298 (2314 1475);
PAINT MONO (2314 1475);
FORCEPROP 2 LAST $XR1 91 
J 0
(2404 1475);
DISPLAY 0.638298 (2404 1475);
PAINT MONO (2404 1475);
FORCEPROP 2 LAST $XR2 92 
J 0
(2494 1475);
DISPLAY 0.638298 (2494 1475);
PAINT MONO (2494 1475);
FORCEPROP 2 LAST $XR3 93 
J 0
(2584 1475);
DISPLAY 0.638298 (2584 1475);
PAINT MONO (2584 1475);
FORCEPROP 2 LAST $XR4 94 
J 0
(2674 1475);
DISPLAY 0.638298 (2674 1475);
PAINT MONO (2674 1475);
FORCEPROP 2 LAST $XR5 95 
J 0
(2764 1475);
DISPLAY 0.638298 (2764 1475);
PAINT MONO (2764 1475);
FORCEPROP 2 LAST $XR6 96 
J 0
(2854 1475);
DISPLAY 0.638298 (2854 1475);
PAINT MONO (2854 1475);
FORCEPROP 2 LAST $XR7 97 
J 0
(2944 1475);
DISPLAY 0.638298 (2944 1475);
PAINT MONO (2944 1475);
FORCEPROP 1 LAST COMMENT_BODY TRUE
J 0
(2050 1375);
DISPLAY 0.872340 (2050 1375);
PAINT GREEN (2050 1375);
DISPLAY INVISIBLE (2050 1375);
FORCEPROP 1 LAST OFFPAGE TRUE
J 0
(2425 1350);
DISPLAY 0.872340 (2425 1350);
PAINT GREEN (2425 1350);
DISPLAY INVISIBLE (2425 1350);
FORCEPROP 2 LAST CDS_LIB standard
J 0
(2100 1475);
PAINT MONO (2100 1475);
DISPLAY INVISIBLE (2100 1475);
FORCEPROP 2 LAST PATH I47
J 0
(2950 1525);
DISPLAY 1.021277 (2950 1525);
DISPLAY INVISIBLE (2950 1525);
FORCEADD OFFPAGE..2
(2100 1625);
FORCEPROP 2 LAST $XR0 90 
J 0
(2289 1625);
DISPLAY 0.638298 (2289 1625);
PAINT MONO (2289 1625);
FORCEPROP 2 LAST $XR1 91 
J 0
(2379 1625);
DISPLAY 0.638298 (2379 1625);
PAINT MONO (2379 1625);
FORCEPROP 2 LAST $XR2 92 
J 0
(2469 1625);
DISPLAY 0.638298 (2469 1625);
PAINT MONO (2469 1625);
FORCEPROP 2 LAST $XR3 93 
J 0
(2559 1625);
DISPLAY 0.638298 (2559 1625);
PAINT MONO (2559 1625);
FORCEPROP 2 LAST $XR4 94 
J 0
(2649 1625);
DISPLAY 0.638298 (2649 1625);
PAINT MONO (2649 1625);
FORCEPROP 2 LAST $XR5 95 
J 0
(2739 1625);
DISPLAY 0.638298 (2739 1625);
PAINT MONO (2739 1625);
FORCEPROP 2 LAST $XR6 96 
J 0
(2829 1625);
DISPLAY 0.638298 (2829 1625);
PAINT MONO (2829 1625);
FORCEPROP 2 LAST $XR7 97 
J 0
(2919 1625);
DISPLAY 0.638298 (2919 1625);
PAINT MONO (2919 1625);
FORCEPROP 1 LAST COMMENT_BODY TRUE
J 0
(2055 1530);
DISPLAY 0.872340 (2055 1530);
PAINT GREEN (2055 1530);
DISPLAY INVISIBLE (2055 1530);
FORCEPROP 1 LAST OFFPAGE TRUE
J 0
(2425 1500);
DISPLAY 0.872340 (2425 1500);
PAINT GREEN (2425 1500);
DISPLAY INVISIBLE (2425 1500);
FORCEPROP 2 LAST CDS_LIB standard
J 0
(2100 1625);
PAINT MONO (2100 1625);
DISPLAY INVISIBLE (2100 1625);
FORCEPROP 2 LAST PATH I48
J 0
(2925 1675);
DISPLAY 1.021277 (2925 1675);
DISPLAY INVISIBLE (2925 1675);
FORCEADD OFFPAGE..3
(2100 1775);
FORCEPROP 2 LAST $XR0 82 
J 0
(2314 1775);
DISPLAY 0.638298 (2314 1775);
PAINT MONO (2314 1775);
FORCEPROP 2 LAST $XR1 83 
J 0
(2404 1775);
DISPLAY 0.638298 (2404 1775);
PAINT MONO (2404 1775);
FORCEPROP 2 LAST $XR2 84 
J 0
(2494 1775);
DISPLAY 0.638298 (2494 1775);
PAINT MONO (2494 1775);
FORCEPROP 2 LAST $XR3 85 
J 0
(2584 1775);
DISPLAY 0.638298 (2584 1775);
PAINT MONO (2584 1775);
FORCEPROP 2 LAST $XR4 86 
J 0
(2674 1775);
DISPLAY 0.638298 (2674 1775);
PAINT MONO (2674 1775);
FORCEPROP 2 LAST $XR5 87 
J 0
(2764 1775);
DISPLAY 0.638298 (2764 1775);
PAINT MONO (2764 1775);
FORCEPROP 2 LAST $XR6 88 
J 0
(2854 1775);
DISPLAY 0.638298 (2854 1775);
PAINT MONO (2854 1775);
FORCEPROP 2 LAST $XR7 89 
J 0
(2944 1775);
DISPLAY 0.638298 (2944 1775);
PAINT MONO (2944 1775);
FORCEPROP 1 LAST COMMENT_BODY TRUE
J 0
(2050 1675);
DISPLAY 0.872340 (2050 1675);
PAINT GREEN (2050 1675);
DISPLAY INVISIBLE (2050 1675);
FORCEPROP 1 LAST OFFPAGE TRUE
J 0
(2425 1650);
DISPLAY 0.872340 (2425 1650);
PAINT GREEN (2425 1650);
DISPLAY INVISIBLE (2425 1650);
FORCEPROP 2 LAST CDS_LIB standard
J 0
(2100 1775);
PAINT MONO (2100 1775);
DISPLAY INVISIBLE (2100 1775);
FORCEPROP 2 LAST PATH I49
J 0
(2950 1825);
DISPLAY 1.021277 (2950 1825);
DISPLAY INVISIBLE (2950 1825);
FORCEADD OFFPAGE..3
R 2
(-3100 1475);
FORCEPROP 2 LAST $XR0 229 
J 0
(-3410 1475);
DISPLAY 0.638298 (-3410 1475);
PAINT MONO (-3410 1475);
FORCEPROP 1 LAST COMMENT_BODY TRUE
J 2
(-3050 1375);
DISPLAY 0.872340 (-3050 1375);
PAINT GREEN (-3050 1375);
DISPLAY INVISIBLE (-3050 1375);
FORCEPROP 1 LAST OFFPAGE TRUE
J 2
(-3425 1350);
DISPLAY 0.872340 (-3425 1350);
DISPLAY INVISIBLE (-3425 1350);
FORCEPROP 2 LAST CDS_LIB standard
J 0
(-3100 1475);
PAINT MONO (-3100 1475);
DISPLAY INVISIBLE (-3100 1475);
FORCEPROP 2 LAST PATH I5
J 0
(-3400 1525);
DISPLAY 1.021277 (-3400 1525);
DISPLAY INVISIBLE (-3400 1525);
FORCEADD OFFPAGE..2
(2100 1925);
FORCEPROP 2 LAST $XR0 82 
J 0
(2289 1925);
DISPLAY 0.638298 (2289 1925);
PAINT MONO (2289 1925);
FORCEPROP 2 LAST $XR1 83 
J 0
(2379 1925);
DISPLAY 0.638298 (2379 1925);
PAINT MONO (2379 1925);
FORCEPROP 2 LAST $XR2 84 
J 0
(2469 1925);
DISPLAY 0.638298 (2469 1925);
PAINT MONO (2469 1925);
FORCEPROP 2 LAST $XR3 85 
J 0
(2559 1925);
DISPLAY 0.638298 (2559 1925);
PAINT MONO (2559 1925);
FORCEPROP 2 LAST $XR4 86 
J 0
(2649 1925);
DISPLAY 0.638298 (2649 1925);
PAINT MONO (2649 1925);
FORCEPROP 2 LAST $XR5 87 
J 0
(2739 1925);
DISPLAY 0.638298 (2739 1925);
PAINT MONO (2739 1925);
FORCEPROP 2 LAST $XR6 88 
J 0
(2829 1925);
DISPLAY 0.638298 (2829 1925);
PAINT MONO (2829 1925);
FORCEPROP 2 LAST $XR7 89 
J 0
(2919 1925);
DISPLAY 0.638298 (2919 1925);
PAINT MONO (2919 1925);
FORCEPROP 1 LAST COMMENT_BODY TRUE
J 0
(2055 1830);
DISPLAY 0.872340 (2055 1830);
PAINT GREEN (2055 1830);
DISPLAY INVISIBLE (2055 1830);
FORCEPROP 1 LAST OFFPAGE TRUE
J 0
(2425 1800);
DISPLAY 0.872340 (2425 1800);
PAINT GREEN (2425 1800);
DISPLAY INVISIBLE (2425 1800);
FORCEPROP 2 LAST CDS_LIB standard
J 0
(2100 1925);
PAINT MONO (2100 1925);
DISPLAY INVISIBLE (2100 1925);
FORCEPROP 2 LAST PATH I50
J 0
(2925 1975);
DISPLAY 1.021277 (2925 1975);
DISPLAY INVISIBLE (2925 1975);
FORCEADD OFFPAGE..3
(875 4225);
FORCEPROP 2 LAST $XR0 229 
J 0
(1089 4225);
DISPLAY 0.638298 (1089 4225);
PAINT MONO (1089 4225);
FORCEPROP 1 LAST COMMENT_BODY TRUE
J 0
(825 4125);
DISPLAY 0.872340 (825 4125);
PAINT GREEN (825 4125);
DISPLAY INVISIBLE (825 4125);
FORCEPROP 1 LAST OFFPAGE TRUE
J 0
(1200 4100);
DISPLAY 0.872340 (1200 4100);
PAINT GREEN (1200 4100);
DISPLAY INVISIBLE (1200 4100);
FORCEPROP 2 LAST CDS_LIB standard
J 0
(875 4225);
PAINT MONO (875 4225);
DISPLAY INVISIBLE (875 4225);
FORCEPROP 2 LAST PATH I51
J 0
(1100 4275);
DISPLAY 1.021277 (1100 4275);
DISPLAY INVISIBLE (1100 4275);
FORCEADD OFFPAGE..2
(875 4275);
FORCEPROP 2 LAST $XR0 229 
J 0
(1064 4275);
DISPLAY 0.638298 (1064 4275);
PAINT MONO (1064 4275);
FORCEPROP 1 LAST COMMENT_BODY TRUE
J 0
(830 4180);
DISPLAY 0.872340 (830 4180);
PAINT GREEN (830 4180);
DISPLAY INVISIBLE (830 4180);
FORCEPROP 1 LAST OFFPAGE TRUE
J 0
(1200 4150);
DISPLAY 0.872340 (1200 4150);
PAINT GREEN (1200 4150);
DISPLAY INVISIBLE (1200 4150);
FORCEPROP 2 LAST CDS_LIB standard
J 0
(875 4275);
PAINT MONO (875 4275);
DISPLAY INVISIBLE (875 4275);
FORCEPROP 2 LAST PATH I52
J 0
(1075 4325);
DISPLAY 1.021277 (1075 4325);
DISPLAY INVISIBLE (1075 4325);
FORCEADD Q_RES..1
(-3700 1200);
FORCEPROP 1 LAST PART_NUMBER CS12002FB06
J 0
(-3800 1150);
DISPLAY 0.404255 (-3800 1150);
DISPLAY INVISIBLE (-3800 1150);
FORCEPROP 1 LAST VALUE 200
J 2
(-3525 1200);
DISPLAY 0.510638 (-3525 1200);
FORCEPROP 1 LAST PACK_TYPE 0402LF
J 0
(-3800 1125);
DISPLAY 0.404255 (-3800 1125);
FORCEPROP 1 LAST MATERIAL CHIP
J 0
(-3450 1200);
DISPLAY 0.510638 (-3450 1200);
PAINT RED (-3450 1200);
FORCEPROP 1 LAST WATTAGE 1/16W
J 2
(-3575 1125);
DISPLAY 0.404255 (-3575 1125);
FORCEPROP 1 LAST TOLERANCE 1%
J 0
(-3525 1200);
DISPLAY 0.510638 (-3525 1200);
FORCEPROP 1 LAST $LOCATION R1821
J 0
(-3975 1200);
DISPLAY 0.638298 (-3975 1200);
FORCEPROP 1 LASTPIN (-3800 1200) $PN 1
J 0
(-3788 1212);
DISPLAY 0.787234 (-3788 1212);
FORCEPROP 1 LASTPIN (-3600 1200) $PN 2
J 0
(-3638 1212);
DISPLAY 0.787234 (-3638 1212);
FORCEPROP 2 LAST CDS_LIB pure_quanta
J 0
(-3700 1200);
PAINT MONO (-3700 1200);
DISPLAY INVISIBLE (-3700 1200);
FORCEPROP 1 LAST PATH I53
J 0
(-3750 1350);
DISPLAY 0.978723 (-3750 1350);
PAINT WHITE (-3750 1350);
DISPLAY INVISIBLE (-3750 1350);
FORCEPROP 2 LAST CDS_LOCATION R1821
J 0
(-3750 1400);
DISPLAY 1.021277 (-3750 1400);
DISPLAY INVISIBLE (-3750 1400);
FORCEPROP 2 LAST $SEC 1
J 0
(-3750 1400);
DISPLAY 0.680851 (-3750 1400);
PAINT MONO (-3750 1400);
DISPLAY INVISIBLE (-3750 1400);
FORCEPROP 2 LAST CDS_SEC 1
J 0
(-3750 1400);
DISPLAY 1.021277 (-3750 1400);
DISPLAY INVISIBLE (-3750 1400);
FORCEADD OFFPAGE..3
R 2
(-3100 1775);
FORCEPROP 2 LAST $XR0 229 
J 0
(-3410 1775);
DISPLAY 0.638298 (-3410 1775);
PAINT MONO (-3410 1775);
FORCEPROP 1 LAST COMMENT_BODY TRUE
J 2
(-3050 1675);
DISPLAY 0.872340 (-3050 1675);
PAINT GREEN (-3050 1675);
DISPLAY INVISIBLE (-3050 1675);
FORCEPROP 1 LAST OFFPAGE TRUE
J 2
(-3425 1650);
DISPLAY 0.872340 (-3425 1650);
DISPLAY INVISIBLE (-3425 1650);
FORCEPROP 2 LAST CDS_LIB standard
J 0
(-3100 1775);
PAINT MONO (-3100 1775);
DISPLAY INVISIBLE (-3100 1775);
FORCEPROP 2 LAST PATH I6
J 0
(-3400 1825);
DISPLAY 1.021277 (-3400 1825);
DISPLAY INVISIBLE (-3400 1825);
FORCEADD OFFPAGE..1
(-3100 1675);
FORCEPROP 2 LAST $XR0 241 
J 0
(-3382 1675);
DISPLAY 0.638298 (-3382 1675);
PAINT MONO (-3382 1675);
FORCEPROP 1 LAST COMMENT_BODY TRUE
J 0
(-2975 1575);
DISPLAY 0.872340 (-2975 1575);
PAINT GREEN (-2975 1575);
DISPLAY INVISIBLE (-2975 1575);
FORCEPROP 1 LAST OFFPAGE TRUE
J 0
(-2775 1550);
DISPLAY 0.872340 (-2775 1550);
PAINT GREEN (-2775 1550);
DISPLAY INVISIBLE (-2775 1550);
FORCEPROP 2 LAST CDS_LIB standard
J 0
(-3100 1675);
PAINT MONO (-3100 1675);
DISPLAY INVISIBLE (-3100 1675);
FORCEPROP 2 LAST PATH I7
J 0
(-3375 1725);
DISPLAY 1.021277 (-3375 1725);
DISPLAY INVISIBLE (-3375 1725);
FORCEADD OFFPAGE..1
(-3100 1625);
FORCEPROP 2 LAST $XR0 229 
J 0
(-3382 1625);
DISPLAY 0.638298 (-3382 1625);
PAINT MONO (-3382 1625);
FORCEPROP 1 LAST COMMENT_BODY TRUE
J 0
(-2975 1525);
DISPLAY 0.872340 (-2975 1525);
PAINT GREEN (-2975 1525);
DISPLAY INVISIBLE (-2975 1525);
FORCEPROP 1 LAST OFFPAGE TRUE
J 0
(-2775 1500);
DISPLAY 0.872340 (-2775 1500);
PAINT GREEN (-2775 1500);
DISPLAY INVISIBLE (-2775 1500);
FORCEPROP 2 LAST CDS_LIB standard
J 0
(-3100 1625);
PAINT MONO (-3100 1625);
DISPLAY INVISIBLE (-3100 1625);
FORCEPROP 2 LAST PATH I8
J 0
(-3375 1675);
DISPLAY 1.021277 (-3375 1675);
DISPLAY INVISIBLE (-3375 1675);
FORCEADD OFFPAGE..3
R 2
(-3100 1825);
FORCEPROP 2 LAST $XR0 241 
J 0
(-3410 1825);
DISPLAY 0.638298 (-3410 1825);
PAINT MONO (-3410 1825);
FORCEPROP 1 LAST COMMENT_BODY TRUE
J 2
(-3050 1725);
DISPLAY 0.872340 (-3050 1725);
PAINT GREEN (-3050 1725);
DISPLAY INVISIBLE (-3050 1725);
FORCEPROP 1 LAST OFFPAGE TRUE
J 2
(-3425 1700);
DISPLAY 0.872340 (-3425 1700);
DISPLAY INVISIBLE (-3425 1700);
FORCEPROP 2 LAST CDS_LIB standard
J 0
(-3100 1825);
PAINT MONO (-3100 1825);
DISPLAY INVISIBLE (-3100 1825);
FORCEPROP 2 LAST PATH I9
J 0
(-3400 1875);
DISPLAY 1.021277 (-3400 1875);
DISPLAY INVISIBLE (-3400 1875);
FORCEADD QUANTA_TITLE_BLOCK_C..1
(3600 -825);
FORCEPROP 0 LAST CDS_CON_LAST_MODIFIED Fri Aug 25 14:03:52 2023
J 0
(1715 -810);
PAINT MONO (1715 -810);
DISPLAY INVISIBLE (1715 -810);
FORCEPROP 2 LAST CUSTOM_TXT_CDS <XR_PAGE_TITLE>
J 0
(-4290 4425);
DISPLAY 0.638298 (-4290 4425);
PAINT PINK (-4290 4425);
DISPLAY INVISIBLE (-4290 4425);
FORCEPROP 2 LAST CUSTOM_TXT_CDS <CON_PAGE_NUM> OF <CON_TOTAL_PAGES>
J 0
(3154 -807);
DISPLAY 0.978723 (3154 -807);
FORCEPROP 2 LAST CUSTOM_TXT_CDS <Q_REV>
J 0
(3416 -722);
DISPLAY 1.212766 (3416 -722);
FORCEPROP 2 LAST CUSTOM_TXT_CDS <Q_NUMBER>
J 0
(2197 -722);
DISPLAY 1.212766 (2197 -722);
FORCEPROP 2 LAST CUSTOM_TXT_CDS <NAME_1>
J 0
(425 -650);
FORCEPROP 2 LAST CUSTOM_TXT_CDS <NAME_2>
J 0
(425 -775);
FORCEPROP 2 LAST CUSTOM_TXT_CDS <Q_PROJ>
J 0
(1218 -723);
DISPLAY 1.212766 (1218 -723);
FORCEPROP 2 LAST CUSTOM_TXT_CDS <CON_LAST_MODIFIED>
J 0
(1715 -810);
DISPLAY 0.978723 (1715 -810);
FORCEPROP 1 LAST Q_TITLE SMBUS - I3C CPU0 SPD
J 0
(-5666 -824);
DISPLAY 2.446809 (-5666 -824);
PAINT GREEN (-5666 -824);
FORCEPROP 1 LAST Q_DEPT 
J 1
(-163 -776);
DISPLAY 1.957447 (-163 -776);
PAINT GREEN (-163 -776);
FORCEPROP 1 LAST COMMENT_BODY TRUE
J 0
(3612 -838);
DISPLAY 0.978723 (3612 -838);
PAINT GREEN (3612 -838);
DISPLAY INVISIBLE (3612 -838);
FORCEPROP 2 LAST CDS_LIB pure_quanta
J 0
(3600 -825);
PAINT MONO (3600 -825);
DISPLAY INVISIBLE (3600 -825);
FORCEPROP 1 LAST CDS_LMAN_SYM_OUTLINE -9475,6775,100,-125
J 0
(3600 -825);
DISPLAY 0.468085 (3600 -825);
PAINT GREEN (3600 -825);
DISPLAY INVISIBLE (3600 -825);
FORCEPROP 2 LAST PAGE_BORDER TRUE
J 0
(-4290 4425);
DISPLAY 0.638298 (-4290 4425);
PAINT PINK (-4290 4425);
DISPLAY INVISIBLE (-4290 4425);
FORCEPROP 2 LAST CDS_XR_PAGE_TITLE CR-229 : @S9S_MB_2U_LIB.S9S_MB_2U(SCH_1):PAGE229
J 0
(-4290 4425);
DISPLAY 0.638298 (-4290 4425);
PAINT PINK (-4290 4425);
DISPLAY INVISIBLE (-4290 4425);
FORCEADD DNS..2
(-1370 670);
PAINT RED (-1370 670);
FORCEPROP 1 LAST COMMENT_BODY TRUE
J 0
(-1370 670);
DISPLAY INVISIBLE (-1370 670);
FORCEPROP 2 LAST CDS_LIB mstr_misc
J 0
(-1370 670);
PAINT MONO (-1370 670);
DISPLAY INVISIBLE (-1370 670);
FORCEADD DNS..2
(-1370 795);
PAINT RED (-1370 795);
FORCEPROP 1 LAST COMMENT_BODY TRUE
J 0
(-1370 795);
DISPLAY INVISIBLE (-1370 795);
FORCEPROP 2 LAST CDS_LIB mstr_misc
J 0
(-1370 795);
PAINT MONO (-1370 795);
DISPLAY INVISIBLE (-1370 795);
FORCEADD DNS..2
(-1370 920);
PAINT RED (-1370 920);
FORCEPROP 1 LAST COMMENT_BODY TRUE
J 0
(-1370 920);
DISPLAY INVISIBLE (-1370 920);
FORCEPROP 2 LAST CDS_LIB mstr_misc
J 0
(-1370 920);
PAINT MONO (-1370 920);
DISPLAY INVISIBLE (-1370 920);
FORCEADD DNS..2
(-1370 1045);
PAINT RED (-1370 1045);
FORCEPROP 1 LAST COMMENT_BODY TRUE
J 0
(-1370 1045);
DISPLAY INVISIBLE (-1370 1045);
FORCEPROP 2 LAST CDS_LIB mstr_misc
J 0
(-1370 1045);
PAINT MONO (-1370 1045);
DISPLAY INVISIBLE (-1370 1045);
FORCEADD DNS..2
(1605 920);
PAINT RED (1605 920);
FORCEPROP 1 LAST COMMENT_BODY TRUE
J 0
(1605 920);
DISPLAY INVISIBLE (1605 920);
FORCEPROP 2 LAST CDS_LIB mstr_misc
J 0
(1605 920);
PAINT MONO (1605 920);
DISPLAY INVISIBLE (1605 920);
WIRE 16 -1 (-975 2525)(-975 2450);
WIRE 16 -1 (-1975 4925)(-1975 4825);
WIRE 16 -1 (1600 1050)(1600 1150);
WIRE 16 -1 (-3050 950)(-3050 1025);
WIRE 16 -1 (-975 1250)(-975 1325);
WIRE 16 -1 (-750 2050)(-750 2150);
WIRE 16 -1 (1600 350)(1600 425);
WIRE 16 -1 (-4800 1200)(-3800 1200);
FORCEPROP 0 LAST CDS_PHYS_NET_NAME FM_SPD_REMOTE_EN_R
J 0
(-4335 1242);
PAINT MONO (-4335 1242);
DISPLAY INVISIBLE (-4335 1242);
FORCEPROP 2 LAST SIG_NAME FM_SPD_REMOTE_EN_R
J 0
(-4710 1210);
DISPLAY 0.680851 (-4710 1210);
PAINT WHITE (-4710 1210);
WIRE 16 2175 (-4000 1050)(-3300 1050);
WIRE 16 2175 (-3300 1350)(-3300 1050);
WIRE 16 2175 (-4000 1350)(-4000 1050);
WIRE 16 2175 (-4000 1350)(-3300 1350);
WIRE 16 -1 (-4800 1375)(-3200 1375);
WIRE 16 -1 (-1650 1375)(-3200 1375);
FORCEPROP 2 LAST SIG_NAME FM_SPD_REMOTE_EN
J 0
(-2935 1385);
DISPLAY 0.680851 (-2935 1385);
PAINT WHITE (-2935 1385);
WIRE 16 -1 (-3200 1375)(-3200 1200);
WIRE 16 -1 (-3600 1200)(-3200 1200);
WIRE 16 -1 (-3050 1225)(-3050 1325);
WIRE 16 -1 (-1650 1325)(-3050 1325);
FORCEPROP 2 LAST SIG_NAME PD_I3C_SPD_DDR_CPU0_OE_N
J 0
(-2935 1335);
DISPLAY 0.680851 (-2935 1335);
PAINT WHITE (-2935 1335);
WIRE 16 -1 (-1475 675)(-2000 675);
WIRE 16 -1 (-2000 1475)(-3050 1475);
FORCEPROP 2 LAST SIG_NAME I3C_SPD_DDREFGH_CPU0_R_SDA
J 0
(-2935 1485);
DISPLAY 0.680851 (-2935 1485);
PAINT WHITE (-2935 1485);
WIRE 16 -1 (-2000 1475)(-2000 675);
WIRE 16 -1 (-1650 1475)(-2000 1475);
WIRE 16 -1 (-1650 1525)(-3050 1525);
FORCEPROP 2 LAST SIG_NAME I3C_SPD_DDREFGH_CPU0_BMC_SDA
J 0
(-2935 1535);
DISPLAY 0.680851 (-2935 1535);
PAINT WHITE (-2935 1535);
WIRE 16 -1 (-775 4275)(825 4275);
FORCEPROP 2 LAST SIG_NAME I3C_SPD_DDRABCD_CPU0_R_SCL
J 0
(-210 4285);
DISPLAY 0.680851 (-210 4285);
PAINT WHITE (-210 4285);
WIRE 16 -1 (2050 1925)(850 1925);
FORCEPROP 2 LAST SIG_NAME I3C_SPD_DDRABCD_CPU0_LVC1_SCL
J 0
(1065 1935);
DISPLAY 0.680851 (1065 1935);
PAINT WHITE (1065 1935);
WIRE 16 -1 (2050 1775)(850 1775);
FORCEPROP 2 LAST SIG_NAME I3C_SPD_DDRABCD_CPU0_LVC1_SDA
J 0
(1065 1785);
DISPLAY 0.680851 (1065 1785);
PAINT WHITE (1065 1785);
WIRE 16 -1 (2050 1625)(850 1625);
FORCEPROP 2 LAST SIG_NAME I3C_SPD_DDREFGH_CPU0_LVC1_SCL
J 0
(1065 1635);
DISPLAY 0.680851 (1065 1635);
PAINT WHITE (1065 1635);
WIRE 16 -1 (2050 1475)(850 1475);
FORCEPROP 2 LAST SIG_NAME I3C_SPD_DDREFGH_CPU0_LVC1_SDA
J 0
(1065 1485);
DISPLAY 0.680851 (1065 1485);
PAINT WHITE (1065 1485);
WIRE 16 -1 (1600 725)(750 725);
FORCEPROP 0 LAST CDS_PHYS_NET_NAME FM_SPD_REMOTE_EN
J 0
(890 773);
PAINT MONO (890 773);
DISPLAY INVISIBLE (890 773);
FORCEPROP 2 LAST SIG_NAME FM_SPD_REMOTE_EN
J 0
(865 735);
DISPLAY 0.808511 (865 735);
PAINT WHITE (865 735);
WIRE 16 -1 (1600 625)(1600 725);
WIRE 16 -1 (1600 850)(1600 725);
WIRE 16 2175 (525 1425)(1025 1425);
WIRE 16 2175 (1025 1550)(1025 1425);
WIRE 16 2175 (525 1550)(525 1425);
WIRE 16 2175 (525 1550)(1025 1550);
WIRE 16 2175 (525 1725)(1025 1725);
WIRE 16 2175 (1025 1850)(1025 1725);
WIRE 16 2175 (525 1850)(525 1725);
WIRE 16 2175 (525 1850)(1025 1850);
WIRE 16 -1 (825 3925)(-775 3925);
FORCEPROP 2 LAST SIG_NAME I3C_SPD_DDREFGH_CPU0_R_SDA
J 0
(-210 3935);
DISPLAY 0.680851 (-210 3935);
PAINT WHITE (-210 3935);
WIRE 16 -1 (825 4225)(-775 4225);
FORCEPROP 2 LAST SIG_NAME I3C_SPD_DDRABCD_CPU0_R_SDA
J 0
(-210 4235);
DISPLAY 0.680851 (-210 4235);
PAINT WHITE (-210 4235);
WIRE 16 -1 (-775 3975)(825 3975);
FORCEPROP 2 LAST SIG_NAME I3C_SPD_DDREFGH_CPU0_R_SCL
J 0
(-210 3985);
DISPLAY 0.680851 (-210 3985);
PAINT WHITE (-210 3985);
WIRE 16 -1 (-1975 4825)(-1975 4700);
WIRE 16 -1 (-1725 4825)(-1975 4825);
WIRE 16 -1 (-1725 4700)(-1725 4825);
WIRE 16 -1 (-1475 4825)(-1725 4825);
WIRE 16 -1 (-1475 4700)(-1475 4825);
WIRE 16 -1 (-1225 4825)(-1225 4700);
WIRE 16 -1 (-1225 4825)(-1475 4825);
WIRE 16 -1 (-1725 4225)(-3050 4225);
FORCEPROP 2 LAST SIG_NAME I3C_SPD_DDRABCD_CPU0_SDA
J 0
(-2935 4235);
DISPLAY 0.680851 (-2935 4235);
PAINT WHITE (-2935 4235);
WIRE 16 -1 (-1725 4500)(-1725 4225);
WIRE 16 -1 (-975 4225)(-1725 4225);
WIRE 16 -1 (-1975 4275)(-3050 4275);
FORCEPROP 2 LAST SIG_NAME I3C_SPD_DDRABCD_CPU0_SCL
J 0
(-2935 4285);
DISPLAY 0.680851 (-2935 4285);
PAINT WHITE (-2935 4285);
WIRE 16 -1 (-1975 4500)(-1975 4275);
WIRE 16 -1 (-975 4275)(-1975 4275);
WIRE 16 -1 (-975 1975)(-1050 1975);
WIRE 16 -1 (-975 2450)(-975 1975);
WIRE 16 -1 (-750 2450)(-975 2450);
WIRE 16 -1 (-750 2350)(-750 2450);
WIRE 16 -1 (-900 1050)(-1275 1050);
WIRE 16 -1 (-900 1925)(-1050 1925);
WIRE 16 -1 (-900 1925)(-900 1050);
WIRE 16 -1 (650 1925)(-900 1925);
FORCEPROP 2 LAST SIG_NAME I3C_SPD_DDRABCD_CPU0_LVC1_R_SCL
J 0
(-585 1935);
DISPLAY 0.680851 (-585 1935);
PAINT WHITE (-585 1935);
WIRE 16 -1 (-1050 1325)(-975 1325);
WIRE 16 -1 (-825 925)(-1275 925);
WIRE 16 -1 (-825 1775)(-1050 1775);
WIRE 16 -1 (-825 1775)(-825 925);
WIRE 16 -1 (650 1775)(-825 1775);
FORCEPROP 2 LAST SIG_NAME I3C_SPD_DDRABCD_CPU0_LVC1_R_SDA
J 0
(-585 1785);
DISPLAY 0.680851 (-585 1785);
PAINT WHITE (-585 1785);
WIRE 16 -1 (-750 800)(-1275 800);
WIRE 16 -1 (-750 1625)(-1050 1625);
WIRE 16 -1 (-750 1625)(-750 800);
WIRE 16 -1 (650 1625)(-750 1625);
FORCEPROP 2 LAST SIG_NAME I3C_SPD_DDREFGH_CPU0_LVC1_R_SCL
J 0
(-585 1635);
DISPLAY 0.680851 (-585 1635);
PAINT WHITE (-585 1635);
WIRE 16 -1 (-675 675)(-1275 675);
WIRE 16 -1 (-675 1475)(-1050 1475);
WIRE 16 -1 (-675 1475)(-675 675);
WIRE 16 -1 (650 1475)(-675 1475);
FORCEPROP 2 LAST SIG_NAME I3C_SPD_DDREFGH_CPU0_LVC1_R_SDA
J 0
(-585 1485);
DISPLAY 0.680851 (-585 1485);
PAINT WHITE (-585 1485);
WIRE 16 -1 (-1775 1050)(-1475 1050);
WIRE 16 -1 (-1775 1925)(-3050 1925);
FORCEPROP 2 LAST SIG_NAME I3C_SPD_DDRABCD_CPU0_R_SCL
J 0
(-2935 1935);
DISPLAY 0.680851 (-2935 1935);
PAINT WHITE (-2935 1935);
WIRE 16 -1 (-1775 1925)(-1775 1050);
WIRE 16 -1 (-1650 1925)(-1775 1925);
WIRE 16 -1 (-1475 925)(-1850 925);
WIRE 16 -1 (-1850 1775)(-3050 1775);
FORCEPROP 2 LAST SIG_NAME I3C_SPD_DDRABCD_CPU0_R_SDA
J 0
(-2935 1785);
DISPLAY 0.680851 (-2935 1785);
PAINT WHITE (-2935 1785);
WIRE 16 -1 (-1850 1775)(-1850 925);
WIRE 16 -1 (-1650 1775)(-1850 1775);
WIRE 16 -1 (-1475 800)(-1925 800);
WIRE 16 -1 (-1925 1625)(-3050 1625);
FORCEPROP 2 LAST SIG_NAME I3C_SPD_DDREFGH_CPU0_R_SCL
J 0
(-2935 1635);
DISPLAY 0.680851 (-2935 1635);
PAINT WHITE (-2935 1635);
WIRE 16 -1 (-1925 1625)(-1925 800);
WIRE 16 -1 (-1650 1625)(-1925 1625);
WIRE 16 -1 (-1650 1975)(-3050 1975);
FORCEPROP 2 LAST SIG_NAME I3C_SPD_DDRABCD_CPU0_BMC_SCL
J 0
(-2935 1985);
DISPLAY 0.680851 (-2935 1985);
PAINT WHITE (-2935 1985);
WIRE 16 -1 (-1650 1825)(-3050 1825);
FORCEPROP 2 LAST SIG_NAME I3C_SPD_DDRABCD_CPU0_BMC_SDA
J 0
(-2935 1835);
DISPLAY 0.680851 (-2935 1835);
PAINT WHITE (-2935 1835);
WIRE 16 -1 (-1225 3925)(-3050 3925);
FORCEPROP 2 LAST SIG_NAME I3C_SPD_DDREFGH_CPU0_SDA
J 0
(-2935 3935);
DISPLAY 0.680851 (-2935 3935);
PAINT WHITE (-2935 3935);
WIRE 16 -1 (-975 3925)(-1225 3925);
WIRE 16 -1 (-1225 4500)(-1225 3925);
WIRE 16 -1 (-1475 3975)(-3050 3975);
FORCEPROP 2 LAST SIG_NAME I3C_SPD_DDREFGH_CPU0_SCL
J 0
(-2935 3985);
DISPLAY 0.680851 (-2935 3985);
PAINT WHITE (-2935 3985);
WIRE 16 -1 (-975 3975)(-1475 3975);
WIRE 16 -1 (-1475 4500)(-1475 3975);
WIRE 16 -1 (-1650 1675)(-3050 1675);
FORCEPROP 2 LAST SIG_NAME I3C_SPD_DDREFGH_CPU0_BMC_SCL
J 0
(-2935 1685);
DISPLAY 0.680851 (-2935 1685);
PAINT WHITE (-2935 1685);
DOT 1 (1600 725);
DOT 1 (-1475 4825);
DOT 1 (-1725 4825);
DOT 1 (-1975 4825);
DOT 1 (-1725 4225);
DOT 1 (-1975 4275);
DOT 1 (-975 2450);
DOT 1 (-1475 3975);
DOT 1 (-1225 3925);
DOT 1 (-750 1625);
DOT 1 (-825 1775);
DOT 1 (-900 1925);
DOT 1 (-675 1475);
DOT 1 (-1775 1925);
DOT 1 (-1850 1775);
DOT 1 (-1925 1625);
DOT 1 (-2000 1475);
DOT 1 (-3200 1375);
FORCENOTE
20221221 CHANGE R692,R694 TO 33.2 OHM
(125 1325) 0;
DISPLAY LEFT (125 1325);
DISPLAY 1.063830 (125 1325);
PAINT WHITE (125 1325);
FORCENOTE
20221201 POP R1821
(-4100 975) 0;
DISPLAY LEFT (-4100 975);
DISPLAY 1.063830 (-4100 975);
PAINT WHITE (-4100 975);
QUIT
